(kicad_sch
	(version 20231120)
	(generator "eeschema")
	(generator_version "8.0")
	(paper "A3")
	(title_block
		(title "GSML Serializer ")
		(date "2024-11-27")
		(rev "1.1.1")
		(company "Antmicro Ltd")
		(comment 1 "www.antmicro.com")
	)
	(bus_alias "CSI"
		(members "CLK_P" "D0_P" "D0_N" "CLK_N" "D1_P" "D1_N" "D2_P" "D2_N" "D3_P"
			"D3_N"
		)
	)
	(junction
		(at 223.52 140.97)
		(diameter 0)
		(color 0 0 0 0)
	)
	(junction
		(at 223.52 91.44)
		(diameter 0)
		(color 0 0 0 0)
	)
	(junction
		(at 223.52 100.33)
		(diameter 0)
		(color 0 0 0 0)
	)
	(junction
		(at 233.68 177.8)
		(diameter 0)
		(color 0 0 0 0)
	)
	(junction
		(at 215.9 91.44)
		(diameter 0)
		(color 0 0 0 0)
	)
	(junction
		(at 223.52 133.35)
		(diameter 0)
		(color 0 0 0 0)
	)
	(junction
		(at 240.03 177.8)
		(diameter 0)
		(color 0 0 0 0)
	)
	(junction
		(at 45.72 204.47)
		(diameter 0)
		(color 0 0 0 0)
	)
	(junction
		(at 50.8 101.6)
		(diameter 0)
		(color 0 0 0 0)
	)
	(junction
		(at 63.5 101.6)
		(diameter 0)
		(color 0 0 0 0)
	)
	(junction
		(at 231.14 91.44)
		(diameter 0)
		(color 0 0 0 0)
	)
	(junction
		(at 215.9 113.03)
		(diameter 0)
		(color 0 0 0 0)
	)
	(junction
		(at 299.72 187.96)
		(diameter 0)
		(color 0 0 0 0)
	)
	(junction
		(at 231.14 133.35)
		(diameter 0)
		(color 0 0 0 0)
	)
	(junction
		(at 215.9 100.33)
		(diameter 0)
		(color 0 0 0 0)
	)
	(junction
		(at 223.52 113.03)
		(diameter 0)
		(color 0 0 0 0)
	)
	(junction
		(at 215.9 140.97)
		(diameter 0)
		(color 0 0 0 0)
	)
	(junction
		(at 231.14 113.03)
		(diameter 0)
		(color 0 0 0 0)
	)
	(junction
		(at 297.18 190.5)
		(diameter 0)
		(color 0 0 0 0)
	)
	(junction
		(at 223.52 120.65)
		(diameter 0)
		(color 0 0 0 0)
	)
	(junction
		(at 57.15 109.22)
		(diameter 0)
		(color 0 0 0 0)
	)
	(junction
		(at 82.55 204.47)
		(diameter 0)
		(color 0 0 0 0)
	)
	(junction
		(at 215.9 133.35)
		(diameter 0)
		(color 0 0 0 0)
	)
	(junction
		(at 215.9 120.65)
		(diameter 0)
		(color 0 0 0 0)
	)
	(bus_entry
		(at 284.48 147.32)
		(size 1.27 -1.27)
		(stroke
			(width 0)
			(type default)
		)
	)
	(bus_entry
		(at 284.48 154.94)
		(size 1.27 -1.27)
		(stroke
			(width 0)
			(type default)
		)
	)
	(bus_entry
		(at 284.48 152.4)
		(size 1.27 -1.27)
		(stroke
			(width 0)
			(type default)
		)
	)
	(bus_entry
		(at 284.48 139.7)
		(size 1.27 -1.27)
		(stroke
			(width 0)
			(type default)
		)
	)
	(bus_entry
		(at 284.48 157.48)
		(size 1.27 -1.27)
		(stroke
			(width 0)
			(type default)
		)
	)
	(bus_entry
		(at 284.48 137.16)
		(size 1.27 -1.27)
		(stroke
			(width 0)
			(type default)
		)
	)
	(bus_entry
		(at 308.61 190.5)
		(size 1.27 -1.27)
		(stroke
			(width 0)
			(type default)
		)
	)
	(bus_entry
		(at 284.48 149.86)
		(size 1.27 -1.27)
		(stroke
			(width 0)
			(type default)
		)
	)
	(bus_entry
		(at 284.48 144.78)
		(size 1.27 -1.27)
		(stroke
			(width 0)
			(type default)
		)
	)
	(bus_entry
		(at 284.48 142.24)
		(size 1.27 -1.27)
		(stroke
			(width 0)
			(type default)
		)
	)
	(bus_entry
		(at 308.61 187.96)
		(size 1.27 -1.27)
		(stroke
			(width 0)
			(type default)
		)
	)
	(bus_entry
		(at 284.48 160.02)
		(size 1.27 -1.27)
		(stroke
			(width 0)
			(type default)
		)
	)
	(wire
		(pts
			(xy 231.14 114.3) (xy 231.14 113.03)
		)
		(stroke
			(width 0)
			(type default)
		)
	)
	(wire
		(pts
			(xy 63.5 107.95) (xy 63.5 109.22)
		)
		(stroke
			(width 0)
			(type default)
		)
	)
	(wire
		(pts
			(xy 220.98 175.26) (xy 243.84 175.26)
		)
		(stroke
			(width 0)
			(type default)
		)
	)
	(bus
		(pts
			(xy 285.75 148.59) (xy 285.75 151.13)
		)
		(stroke
			(width 0)
			(type default)
		)
	)
	(wire
		(pts
			(xy 223.52 134.62) (xy 223.52 133.35)
		)
		(stroke
			(width 0)
			(type default)
		)
	)
	(wire
		(pts
			(xy 290.83 190.5) (xy 297.18 190.5)
		)
		(stroke
			(width 0)
			(type default)
		)
	)
	(wire
		(pts
			(xy 215.9 142.24) (xy 215.9 140.97)
		)
		(stroke
			(width 0)
			(type default)
		)
	)
	(bus
		(pts
			(xy 285.75 143.51) (xy 285.75 146.05)
		)
		(stroke
			(width 0)
			(type default)
		)
	)
	(wire
		(pts
			(xy 240.03 185.42) (xy 240.03 184.15)
		)
		(stroke
			(width 0)
			(type default)
		)
	)
	(wire
		(pts
			(xy 215.9 114.3) (xy 215.9 113.03)
		)
		(stroke
			(width 0)
			(type default)
		)
	)
	(wire
		(pts
			(xy 234.95 171.45) (xy 234.95 172.72)
		)
		(stroke
			(width 0)
			(type default)
		)
	)
	(wire
		(pts
			(xy 222.25 165.1) (xy 222.25 166.37)
		)
		(stroke
			(width 0)
			(type default)
		)
	)
	(wire
		(pts
			(xy 271.78 154.94) (xy 284.48 154.94)
		)
		(stroke
			(width 0)
			(type default)
		)
	)
	(wire
		(pts
			(xy 240.03 91.44) (xy 231.14 91.44)
		)
		(stroke
			(width 0)
			(type default)
		)
	)
	(wire
		(pts
			(xy 231.14 113.03) (xy 238.76 113.03)
		)
		(stroke
			(width 0)
			(type default)
		)
	)
	(wire
		(pts
			(xy 223.52 100.33) (xy 231.14 100.33)
		)
		(stroke
			(width 0)
			(type default)
		)
	)
	(wire
		(pts
			(xy 243.84 154.94) (xy 231.14 154.94)
		)
		(stroke
			(width 0)
			(type default)
		)
	)
	(wire
		(pts
			(xy 242.57 193.04) (xy 242.57 190.5)
		)
		(stroke
			(width 0)
			(type default)
		)
	)
	(wire
		(pts
			(xy 45.72 213.36) (xy 45.72 212.09)
		)
		(stroke
			(width 0)
			(type default)
		)
	)
	(wire
		(pts
			(xy 238.76 165.1) (xy 243.84 165.1)
		)
		(stroke
			(width 0)
			(type default)
		)
	)
	(wire
		(pts
			(xy 215.9 100.33) (xy 223.52 100.33)
		)
		(stroke
			(width 0)
			(type default)
		)
	)
	(wire
		(pts
			(xy 243.84 158.75) (xy 231.14 158.75)
		)
		(stroke
			(width 0)
			(type default)
		)
	)
	(wire
		(pts
			(xy 82.55 213.36) (xy 82.55 212.09)
		)
		(stroke
			(width 0)
			(type default)
		)
	)
	(wire
		(pts
			(xy 240.03 177.8) (xy 243.84 177.8)
		)
		(stroke
			(width 0)
			(type default)
		)
	)
	(bus
		(pts
			(xy 285.75 156.21) (xy 285.75 158.75)
		)
		(stroke
			(width 0)
			(type default)
		)
	)
	(wire
		(pts
			(xy 50.8 109.22) (xy 57.15 109.22)
		)
		(stroke
			(width 0)
			(type default)
		)
	)
	(wire
		(pts
			(xy 271.78 139.7) (xy 284.48 139.7)
		)
		(stroke
			(width 0)
			(type default)
		)
	)
	(wire
		(pts
			(xy 271.78 142.24) (xy 284.48 142.24)
		)
		(stroke
			(width 0)
			(type default)
		)
	)
	(wire
		(pts
			(xy 82.55 195.58) (xy 82.55 196.85)
		)
		(stroke
			(width 0)
			(type default)
		)
	)
	(bus
		(pts
			(xy 285.75 138.43) (xy 285.75 140.97)
		)
		(stroke
			(width 0)
			(type default)
		)
	)
	(wire
		(pts
			(xy 223.52 100.33) (xy 223.52 97.79)
		)
		(stroke
			(width 0)
			(type default)
		)
	)
	(wire
		(pts
			(xy 271.78 144.78) (xy 284.48 144.78)
		)
		(stroke
			(width 0)
			(type default)
		)
	)
	(bus
		(pts
			(xy 285.75 140.97) (xy 285.75 143.51)
		)
		(stroke
			(width 0)
			(type default)
		)
	)
	(wire
		(pts
			(xy 215.9 90.17) (xy 215.9 91.44)
		)
		(stroke
			(width 0)
			(type default)
		)
	)
	(wire
		(pts
			(xy 231.14 139.7) (xy 231.14 140.97)
		)
		(stroke
			(width 0)
			(type default)
		)
	)
	(bus
		(pts
			(xy 311.15 185.42) (xy 309.88 185.42)
		)
		(stroke
			(width 0)
			(type default)
		)
	)
	(wire
		(pts
			(xy 215.9 92.71) (xy 215.9 91.44)
		)
		(stroke
			(width 0)
			(type default)
		)
	)
	(wire
		(pts
			(xy 63.5 88.9) (xy 63.5 91.44)
		)
		(stroke
			(width 0)
			(type default)
		)
	)
	(wire
		(pts
			(xy 223.52 120.65) (xy 231.14 120.65)
		)
		(stroke
			(width 0)
			(type default)
		)
	)
	(wire
		(pts
			(xy 215.9 139.7) (xy 215.9 140.97)
		)
		(stroke
			(width 0)
			(type default)
		)
	)
	(bus
		(pts
			(xy 289.56 134.62) (xy 285.75 134.62)
		)
		(stroke
			(width 0)
			(type default)
		)
	)
	(wire
		(pts
			(xy 297.18 185.42) (xy 297.18 190.5)
		)
		(stroke
			(width 0)
			(type default)
		)
	)
	(wire
		(pts
			(xy 220.98 184.15) (xy 220.98 185.42)
		)
		(stroke
			(width 0)
			(type default)
		)
	)
	(wire
		(pts
			(xy 215.9 134.62) (xy 215.9 133.35)
		)
		(stroke
			(width 0)
			(type default)
		)
	)
	(wire
		(pts
			(xy 222.25 158.75) (xy 222.25 160.02)
		)
		(stroke
			(width 0)
			(type default)
		)
	)
	(wire
		(pts
			(xy 233.68 177.8) (xy 227.33 177.8)
		)
		(stroke
			(width 0)
			(type default)
		)
	)
	(wire
		(pts
			(xy 63.5 101.6) (xy 63.5 102.87)
		)
		(stroke
			(width 0)
			(type default)
		)
	)
	(wire
		(pts
			(xy 223.52 140.97) (xy 215.9 140.97)
		)
		(stroke
			(width 0)
			(type default)
		)
	)
	(wire
		(pts
			(xy 223.52 113.03) (xy 231.14 113.03)
		)
		(stroke
			(width 0)
			(type default)
		)
	)
	(wire
		(pts
			(xy 290.83 182.88) (xy 299.72 182.88)
		)
		(stroke
			(width 0)
			(type default)
		)
	)
	(wire
		(pts
			(xy 223.52 133.35) (xy 215.9 133.35)
		)
		(stroke
			(width 0)
			(type default)
		)
	)
	(wire
		(pts
			(xy 271.78 182.88) (xy 285.75 182.88)
		)
		(stroke
			(width 0)
			(type default)
		)
	)
	(wire
		(pts
			(xy 290.83 187.96) (xy 299.72 187.96)
		)
		(stroke
			(width 0)
			(type default)
		)
	)
	(wire
		(pts
			(xy 271.78 137.16) (xy 284.48 137.16)
		)
		(stroke
			(width 0)
			(type default)
		)
	)
	(wire
		(pts
			(xy 271.78 149.86) (xy 284.48 149.86)
		)
		(stroke
			(width 0)
			(type default)
		)
	)
	(bus
		(pts
			(xy 285.75 146.05) (xy 285.75 148.59)
		)
		(stroke
			(width 0)
			(type default)
		)
	)
	(wire
		(pts
			(xy 82.55 201.93) (xy 82.55 204.47)
		)
		(stroke
			(width 0)
			(type default)
		)
	)
	(wire
		(pts
			(xy 233.68 179.07) (xy 233.68 177.8)
		)
		(stroke
			(width 0)
			(type default)
		)
	)
	(wire
		(pts
			(xy 50.8 88.9) (xy 50.8 101.6)
		)
		(stroke
			(width 0)
			(type default)
		)
	)
	(wire
		(pts
			(xy 231.14 119.38) (xy 231.14 120.65)
		)
		(stroke
			(width 0)
			(type default)
		)
	)
	(wire
		(pts
			(xy 60.96 101.6) (xy 63.5 101.6)
		)
		(stroke
			(width 0)
			(type default)
		)
	)
	(wire
		(pts
			(xy 271.78 167.64) (xy 284.48 167.64)
		)
		(stroke
			(width 0)
			(type default)
		)
	)
	(wire
		(pts
			(xy 223.52 91.44) (xy 231.14 91.44)
		)
		(stroke
			(width 0)
			(type default)
		)
	)
	(wire
		(pts
			(xy 271.78 177.8) (xy 276.86 177.8)
		)
		(stroke
			(width 0)
			(type default)
		)
	)
	(wire
		(pts
			(xy 242.57 190.5) (xy 243.84 190.5)
		)
		(stroke
			(width 0)
			(type default)
		)
	)
	(wire
		(pts
			(xy 243.84 149.86) (xy 236.22 149.86)
		)
		(stroke
			(width 0)
			(type default)
		)
	)
	(wire
		(pts
			(xy 290.83 185.42) (xy 297.18 185.42)
		)
		(stroke
			(width 0)
			(type default)
		)
	)
	(bus
		(pts
			(xy 285.75 135.89) (xy 285.75 138.43)
		)
		(stroke
			(width 0)
			(type default)
		)
	)
	(wire
		(pts
			(xy 271.78 165.1) (xy 275.59 165.1)
		)
		(stroke
			(width 0)
			(type default)
		)
	)
	(wire
		(pts
			(xy 215.9 91.44) (xy 223.52 91.44)
		)
		(stroke
			(width 0)
			(type default)
		)
	)
	(wire
		(pts
			(xy 50.8 101.6) (xy 50.8 102.87)
		)
		(stroke
			(width 0)
			(type default)
		)
	)
	(wire
		(pts
			(xy 45.72 195.58) (xy 45.72 196.85)
		)
		(stroke
			(width 0)
			(type default)
		)
	)
	(wire
		(pts
			(xy 237.49 133.35) (xy 231.14 133.35)
		)
		(stroke
			(width 0)
			(type default)
		)
	)
	(wire
		(pts
			(xy 220.98 179.07) (xy 220.98 175.26)
		)
		(stroke
			(width 0)
			(type default)
		)
	)
	(wire
		(pts
			(xy 215.9 120.65) (xy 223.52 120.65)
		)
		(stroke
			(width 0)
			(type default)
		)
	)
	(wire
		(pts
			(xy 215.9 113.03) (xy 223.52 113.03)
		)
		(stroke
			(width 0)
			(type default)
		)
	)
	(wire
		(pts
			(xy 271.78 147.32) (xy 284.48 147.32)
		)
		(stroke
			(width 0)
			(type default)
		)
	)
	(wire
		(pts
			(xy 271.78 175.26) (xy 279.4 175.26)
		)
		(stroke
			(width 0)
			(type default)
		)
	)
	(wire
		(pts
			(xy 231.14 140.97) (xy 223.52 140.97)
		)
		(stroke
			(width 0)
			(type default)
		)
	)
	(wire
		(pts
			(xy 271.78 187.96) (xy 285.75 187.96)
		)
		(stroke
			(width 0)
			(type default)
		)
	)
	(wire
		(pts
			(xy 215.9 119.38) (xy 215.9 120.65)
		)
		(stroke
			(width 0)
			(type default)
		)
	)
	(bus
		(pts
			(xy 285.75 151.13) (xy 285.75 153.67)
		)
		(stroke
			(width 0)
			(type default)
		)
	)
	(wire
		(pts
			(xy 233.68 185.42) (xy 233.68 184.15)
		)
		(stroke
			(width 0)
			(type default)
		)
	)
	(wire
		(pts
			(xy 223.52 92.71) (xy 223.52 91.44)
		)
		(stroke
			(width 0)
			(type default)
		)
	)
	(wire
		(pts
			(xy 57.15 109.22) (xy 57.15 106.68)
		)
		(stroke
			(width 0)
			(type default)
		)
	)
	(wire
		(pts
			(xy 238.76 139.7) (xy 238.76 113.03)
		)
		(stroke
			(width 0)
			(type default)
		)
	)
	(polyline
		(pts
			(xy 12.7 132.08) (xy 129.54 132.08)
		)
		(stroke
			(width 0)
			(type dash)
		)
	)
	(wire
		(pts
			(xy 50.8 107.95) (xy 50.8 109.22)
		)
		(stroke
			(width 0)
			(type default)
		)
	)
	(wire
		(pts
			(xy 45.72 201.93) (xy 45.72 204.47)
		)
		(stroke
			(width 0)
			(type default)
		)
	)
	(wire
		(pts
			(xy 215.9 113.03) (xy 215.9 111.76)
		)
		(stroke
			(width 0)
			(type default)
		)
	)
	(wire
		(pts
			(xy 243.84 142.24) (xy 237.49 142.24)
		)
		(stroke
			(width 0)
			(type default)
		)
	)
	(wire
		(pts
			(xy 240.03 137.16) (xy 240.03 91.44)
		)
		(stroke
			(width 0)
			(type default)
		)
	)
	(wire
		(pts
			(xy 271.78 180.34) (xy 276.86 180.34)
		)
		(stroke
			(width 0)
			(type default)
		)
	)
	(wire
		(pts
			(xy 234.95 165.1) (xy 234.95 166.37)
		)
		(stroke
			(width 0)
			(type default)
		)
	)
	(wire
		(pts
			(xy 238.76 167.64) (xy 243.84 167.64)
		)
		(stroke
			(width 0)
			(type default)
		)
	)
	(wire
		(pts
			(xy 231.14 133.35) (xy 223.52 133.35)
		)
		(stroke
			(width 0)
			(type default)
		)
	)
	(wire
		(pts
			(xy 271.78 152.4) (xy 284.48 152.4)
		)
		(stroke
			(width 0)
			(type default)
		)
	)
	(wire
		(pts
			(xy 299.72 182.88) (xy 299.72 187.96)
		)
		(stroke
			(width 0)
			(type default)
		)
	)
	(wire
		(pts
			(xy 240.03 179.07) (xy 240.03 177.8)
		)
		(stroke
			(width 0)
			(type default)
		)
	)
	(bus
		(pts
			(xy 285.75 134.62) (xy 285.75 135.89)
		)
		(stroke
			(width 0)
			(type default)
		)
	)
	(wire
		(pts
			(xy 215.9 121.92) (xy 215.9 120.65)
		)
		(stroke
			(width 0)
			(type default)
		)
	)
	(wire
		(pts
			(xy 231.14 100.33) (xy 231.14 97.79)
		)
		(stroke
			(width 0)
			(type default)
		)
	)
	(wire
		(pts
			(xy 271.78 172.72) (xy 279.4 172.72)
		)
		(stroke
			(width 0)
			(type default)
		)
	)
	(bus
		(pts
			(xy 285.75 153.67) (xy 285.75 156.21)
		)
		(stroke
			(width 0)
			(type default)
		)
	)
	(polyline
		(pts
			(xy 130.81 13.97) (xy 130.81 285.75)
		)
		(stroke
			(width 0)
			(type dash)
		)
	)
	(wire
		(pts
			(xy 243.84 139.7) (xy 238.76 139.7)
		)
		(stroke
			(width 0)
			(type default)
		)
	)
	(wire
		(pts
			(xy 271.78 157.48) (xy 284.48 157.48)
		)
		(stroke
			(width 0)
			(type default)
		)
	)
	(bus
		(pts
			(xy 309.88 186.69) (xy 309.88 189.23)
		)
		(stroke
			(width 0)
			(type default)
		)
	)
	(wire
		(pts
			(xy 223.52 140.97) (xy 223.52 139.7)
		)
		(stroke
			(width 0)
			(type default)
		)
	)
	(wire
		(pts
			(xy 63.5 96.52) (xy 63.5 101.6)
		)
		(stroke
			(width 0)
			(type default)
		)
	)
	(wire
		(pts
			(xy 243.84 157.48) (xy 243.84 158.75)
		)
		(stroke
			(width 0)
			(type default)
		)
	)
	(wire
		(pts
			(xy 271.78 190.5) (xy 285.75 190.5)
		)
		(stroke
			(width 0)
			(type default)
		)
	)
	(bus
		(pts
			(xy 309.88 185.42) (xy 309.88 186.69)
		)
		(stroke
			(width 0)
			(type default)
		)
	)
	(wire
		(pts
			(xy 215.9 100.33) (xy 215.9 101.6)
		)
		(stroke
			(width 0)
			(type default)
		)
	)
	(wire
		(pts
			(xy 297.18 190.5) (xy 308.61 190.5)
		)
		(stroke
			(width 0)
			(type default)
		)
	)
	(wire
		(pts
			(xy 215.9 100.33) (xy 215.9 97.79)
		)
		(stroke
			(width 0)
			(type default)
		)
	)
	(wire
		(pts
			(xy 227.33 179.07) (xy 227.33 177.8)
		)
		(stroke
			(width 0)
			(type default)
		)
	)
	(wire
		(pts
			(xy 227.33 185.42) (xy 227.33 184.15)
		)
		(stroke
			(width 0)
			(type default)
		)
	)
	(wire
		(pts
			(xy 223.52 120.65) (xy 223.52 119.38)
		)
		(stroke
			(width 0)
			(type default)
		)
	)
	(wire
		(pts
			(xy 45.72 204.47) (xy 53.34 204.47)
		)
		(stroke
			(width 0)
			(type default)
		)
	)
	(wire
		(pts
			(xy 271.78 170.18) (xy 284.48 170.18)
		)
		(stroke
			(width 0)
			(type default)
		)
	)
	(wire
		(pts
			(xy 271.78 185.42) (xy 285.75 185.42)
		)
		(stroke
			(width 0)
			(type default)
		)
	)
	(wire
		(pts
			(xy 240.03 177.8) (xy 233.68 177.8)
		)
		(stroke
			(width 0)
			(type default)
		)
	)
	(wire
		(pts
			(xy 299.72 187.96) (xy 308.61 187.96)
		)
		(stroke
			(width 0)
			(type default)
		)
	)
	(wire
		(pts
			(xy 226.06 154.94) (xy 219.71 154.94)
		)
		(stroke
			(width 0)
			(type default)
		)
	)
	(wire
		(pts
			(xy 231.14 91.44) (xy 231.14 92.71)
		)
		(stroke
			(width 0)
			(type default)
		)
	)
	(wire
		(pts
			(xy 82.55 204.47) (xy 90.17 204.47)
		)
		(stroke
			(width 0)
			(type default)
		)
	)
	(wire
		(pts
			(xy 237.49 142.24) (xy 237.49 133.35)
		)
		(stroke
			(width 0)
			(type default)
		)
	)
	(wire
		(pts
			(xy 45.72 204.47) (xy 45.72 207.01)
		)
		(stroke
			(width 0)
			(type default)
		)
	)
	(wire
		(pts
			(xy 223.52 114.3) (xy 223.52 113.03)
		)
		(stroke
			(width 0)
			(type default)
		)
	)
	(wire
		(pts
			(xy 82.55 204.47) (xy 82.55 207.01)
		)
		(stroke
			(width 0)
			(type default)
		)
	)
	(wire
		(pts
			(xy 57.15 110.49) (xy 57.15 109.22)
		)
		(stroke
			(width 0)
			(type default)
		)
	)
	(wire
		(pts
			(xy 271.78 160.02) (xy 284.48 160.02)
		)
		(stroke
			(width 0)
			(type default)
		)
	)
	(wire
		(pts
			(xy 215.9 133.35) (xy 215.9 132.08)
		)
		(stroke
			(width 0)
			(type default)
		)
	)
	(wire
		(pts
			(xy 57.15 109.22) (xy 63.5 109.22)
		)
		(stroke
			(width 0)
			(type default)
		)
	)
	(wire
		(pts
			(xy 231.14 134.62) (xy 231.14 133.35)
		)
		(stroke
			(width 0)
			(type default)
		)
	)
	(wire
		(pts
			(xy 243.84 137.16) (xy 240.03 137.16)
		)
		(stroke
			(width 0)
			(type default)
		)
	)
	(wire
		(pts
			(xy 53.34 101.6) (xy 50.8 101.6)
		)
		(stroke
			(width 0)
			(type default)
		)
	)
	(wire
		(pts
			(xy 234.95 172.72) (xy 243.84 172.72)
		)
		(stroke
			(width 0)
			(type default)
		)
	)
	(wire
		(pts
			(xy 226.06 158.75) (xy 222.25 158.75)
		)
		(stroke
			(width 0)
			(type default)
		)
	)
	(text "CFG0 - I2C address config\nR1 = OPEN, R2 = 10k\nI2C; Address = 0x40 (7-bit); \nClock= RoR"
		(exclude_from_sim no)
		(at 38.1 187.325 0)
		(effects
			(font
				(size 1.27 1.27)
			)
			(justify left bottom)
		)
	)
	(text "Decoupling capacitors as close as possible to supply pins"
		(exclude_from_sim no)
		(at 198.12 82.55 0)
		(effects
			(font
				(size 1.27 1.27)
			)
			(justify left bottom)
		)
	)
	(text "Cinx1 = 3 pF (from MAX96717 data sheet)\nCtrace = 2 pF (estimated)\nCinx2 = 1 pF (from MAX96717 data sheet)\nCL = 18 pF (from crystal data sheet)\nCx1total = Cinx1 + CL1 + Ctrace\nCx2total = Cinx2 + CL2 + Ctrace\nCL = (Cx1total * Cx2total) / (Cx1total + Cx2total)\n\nCL1 = 33 pF\nCl2 = 33 pF\nCX1total = 38 pF\nCx2total = 36 pF\nCL = 18.5 pF (meets the requirements)"
		(exclude_from_sim no)
		(at 40.64 76.2 0)
		(effects
			(font
				(size 1.27 1.27)
			)
			(justify left bottom)
		)
	)
	(text "CFG1 - GMSL mode config\nR1 = 10k, R2 = OPEN\nmode = COAX 6Gbps; Pixel mode"
		(exclude_from_sim no)
		(at 72.39 187.325 0)
		(effects
			(font
				(size 1.27 1.27)
			)
			(justify left bottom)
		)
	)
	(text "Serializer"
		(exclude_from_sim no)
		(at 262.255 79.375 0)
		(effects
			(font
				(size 2.54 2.54)
				(thickness 0.508)
				(bold yes)
			)
			(justify left bottom)
		)
	)
	(text "Crystal"
		(exclude_from_sim no)
		(at 40.64 40.64 0)
		(effects
			(font
				(size 2.54 2.54)
				(thickness 0.508)
				(bold yes)
			)
			(justify left bottom)
		)
	)
	(text "Config pins"
		(exclude_from_sim no)
		(at 35.56 170.18 0)
		(effects
			(font
				(size 2.54 2.54)
				(thickness 0.4)
				(bold yes)
			)
			(justify left bottom)
		)
	)
	(text "Link capacitors as close as possible to SIO pins"
		(exclude_from_sim no)
		(at 167.64 158.75 0)
		(effects
			(font
				(size 1.27 1.27)
			)
			(justify left bottom)
		)
	)
	(text "Crystal and crystal load \ncapacitors as close as \npossible to X1 X2 pins"
		(exclude_from_sim no)
		(at 77.47 105.41 0)
		(effects
			(font
				(size 1.27 1.27)
			)
			(justify left bottom)
		)
	)
	(label "X2"
		(at 238.76 167.64 0)
		(fields_autoplaced yes)
		(effects
			(font
				(size 1.27 1.27)
			)
			(justify left bottom)
		)
	)
	(label "X2"
		(at 63.5 88.9 270)
		(fields_autoplaced yes)
		(effects
			(font
				(size 1.27 1.27)
			)
			(justify right bottom)
		)
	)
	(label "I2C.SCL"
		(at 300.99 190.5 0)
		(fields_autoplaced yes)
		(effects
			(font
				(size 1.27 1.27)
			)
			(justify left bottom)
		)
	)
	(label "CSI.D3_P"
		(at 284.48 157.48 180)
		(fields_autoplaced yes)
		(effects
			(font
				(size 1.27 1.27)
			)
			(justify right bottom)
		)
	)
	(label "CFG0"
		(at 53.34 204.47 180)
		(fields_autoplaced yes)
		(effects
			(font
				(size 1.27 1.27)
			)
			(justify right bottom)
		)
	)
	(label "CSI.D1_N"
		(at 284.48 149.86 180)
		(fields_autoplaced yes)
		(effects
			(font
				(size 1.27 1.27)
			)
			(justify right bottom)
		)
	)
	(label "CFG0"
		(at 284.48 167.64 180)
		(fields_autoplaced yes)
		(effects
			(font
				(size 1.27 1.27)
			)
			(justify right bottom)
		)
	)
	(label "CSI.CLK_N"
		(at 284.48 139.7 180)
		(fields_autoplaced yes)
		(effects
			(font
				(size 1.27 1.27)
			)
			(justify right bottom)
		)
	)
	(label "I2C.SDA"
		(at 300.99 187.96 0)
		(fields_autoplaced yes)
		(effects
			(font
				(size 1.27 1.27)
			)
			(justify left bottom)
		)
	)
	(label "CSI.D2_P"
		(at 284.48 152.4 180)
		(fields_autoplaced yes)
		(effects
			(font
				(size 1.27 1.27)
			)
			(justify right bottom)
		)
	)
	(label "CSI.CLK_P"
		(at 284.48 137.16 180)
		(fields_autoplaced yes)
		(effects
			(font
				(size 1.27 1.27)
			)
			(justify right bottom)
		)
	)
	(label "CSI.D0_N"
		(at 284.48 144.78 180)
		(fields_autoplaced yes)
		(effects
			(font
				(size 1.27 1.27)
			)
			(justify right bottom)
		)
	)
	(label "CSI.D0_P"
		(at 284.48 142.24 180)
		(fields_autoplaced yes)
		(effects
			(font
				(size 1.27 1.27)
			)
			(justify right bottom)
		)
	)
	(label "X1"
		(at 238.76 165.1 0)
		(fields_autoplaced yes)
		(effects
			(font
				(size 1.27 1.27)
			)
			(justify left bottom)
		)
	)
	(label "CSI.D3_N"
		(at 284.48 160.02 180)
		(fields_autoplaced yes)
		(effects
			(font
				(size 1.27 1.27)
			)
			(justify right bottom)
		)
	)
	(label "CFG1"
		(at 90.17 204.47 180)
		(fields_autoplaced yes)
		(effects
			(font
				(size 1.27 1.27)
			)
			(justify right bottom)
		)
	)
	(label "X1"
		(at 50.8 88.9 270)
		(fields_autoplaced yes)
		(effects
			(font
				(size 1.27 1.27)
			)
			(justify right bottom)
		)
	)
	(label "CSI.D2_N"
		(at 284.48 154.94 180)
		(fields_autoplaced yes)
		(effects
			(font
				(size 1.27 1.27)
			)
			(justify right bottom)
		)
	)
	(label "X2_R"
		(at 63.5 100.33 0)
		(fields_autoplaced yes)
		(effects
			(font
				(size 1.27 1.27)
			)
			(justify left bottom)
		)
	)
	(label "CSI.D1_P"
		(at 284.48 147.32 180)
		(fields_autoplaced yes)
		(effects
			(font
				(size 1.27 1.27)
			)
			(justify right bottom)
		)
	)
	(label "CFG1"
		(at 284.48 170.18 180)
		(fields_autoplaced yes)
		(effects
			(font
				(size 1.27 1.27)
			)
			(justify right bottom)
		)
	)
	(hierarchical_label "I2C{I2C}"
		(shape bidirectional)
		(at 311.15 185.42 0)
		(fields_autoplaced yes)
		(effects
			(font
				(size 1.27 1.27)
			)
			(justify left)
		)
	)
	(hierarchical_label "GPIO3"
		(shape output)
		(at 279.4 172.72 0)
		(fields_autoplaced yes)
		(effects
			(font
				(size 1.27 1.27)
			)
			(justify left)
		)
	)
	(hierarchical_label "VREF"
		(shape input)
		(at 236.22 149.86 180)
		(fields_autoplaced yes)
		(effects
			(font
				(size 1.27 1.27)
			)
			(justify right)
		)
	)
	(hierarchical_label "GPIO4"
		(shape output)
		(at 279.4 175.26 0)
		(fields_autoplaced yes)
		(effects
			(font
				(size 1.27 1.27)
			)
			(justify left)
		)
	)
	(hierarchical_label "CSI{CSI}"
		(shape input)
		(at 289.56 134.62 0)
		(fields_autoplaced yes)
		(effects
			(font
				(size 1.27 1.27)
			)
			(justify left)
		)
	)
	(hierarchical_label "SIO_P"
		(shape bidirectional)
		(at 219.71 154.94 180)
		(fields_autoplaced yes)
		(effects
			(font
				(size 1.27 1.27)
			)
			(justify right)
		)
	)
	(symbol
		(lib_id "antmicroCapacitors0402:C_33p_0402")
		(at 50.8 107.95 90)
		(unit 1)
		(exclude_from_sim no)
		(in_bom yes)
		(on_board yes)
		(dnp no)
		(property "Reference" "C16"
			(at 45.72 103.505 90)
			(effects
				(font
					(size 1.27 1.27)
					(thickness 0.15)
				)
				(justify right)
			)
		)
		(property "Value" "C_33p_0402"
			(at 60.96 87.63 0)
			(effects
				(font
					(size 1.27 1.27)
					(thickness 0.15)
				)
				(justify left bottom)
				(hide yes)
			)
		)
		(property "Footprint" "antmicro-footprints:C_0402_1005Metric"
			(at 63.5 87.63 0)
			(effects
				(font
					(size 1.27 1.27)
					(thickness 0.15)
				)
				(justify left bottom)
				(hide yes)
			)
		)
		(property "Datasheet" "https://spicat.kyocera-avx.com/product/mlcc/chartview/04025A330FAT2A/"
			(at 66.04 87.63 0)
			(effects
				(font
					(size 1.27 1.27)
					(thickness 0.15)
				)
				(justify left bottom)
				(hide yes)
			)
		)
		(property "Description" ""
			(at 50.8 107.95 0)
			(effects
				(font
					(size 1.27 1.27)
				)
				(hide yes)
			)
		)
		(property "MPN" "04025A330FAT2A"
			(at 68.58 87.63 0)
			(effects
				(font
					(size 1.27 1.27)
					(thickness 0.15)
				)
				(justify left bottom)
				(hide yes)
			)
		)
		(property "Manufacturer" "KYOCERA AVX"
			(at 71.12 87.63 0)
			(effects
				(font
					(size 1.27 1.27)
					(thickness 0.15)
				)
				(justify left bottom)
				(hide yes)
			)
		)
		(property "License" "Apache-2.0"
			(at 73.66 87.63 0)
			(effects
				(font
					(size 1.27 1.27)
					(thickness 0.15)
				)
				(justify left bottom)
				(hide yes)
			)
		)
		(property "Author" "Antmicro"
			(at 76.2 87.63 0)
			(effects
				(font
					(size 1.27 1.27)
					(thickness 0.15)
				)
				(justify left bottom)
				(hide yes)
			)
		)
		(property "Val" "33p"
			(at 45.72 106.68 90)
			(effects
				(font
					(size 1.27 1.27)
					(thickness 0.15)
				)
				(justify right)
			)
		)
		(property "Voltage" ""
			(at 78.74 87.63 0)
			(effects
				(font
					(size 1.27 1.27)
				)
				(justify left bottom)
				(hide yes)
			)
		)
		(property "Dielectric" ""
			(at 81.28 87.63 0)
			(effects
				(font
					(size 1.27 1.27)
				)
				(justify left bottom)
				(hide yes)
			)
		)
		(pin "1"
		)
		(pin "2"
		)
		(instances
			(project "gmsl-serializer"
				(path ""
					(reference "C16")
					(unit 1)
				)
			)
		)
	)
	(symbol
		(lib_id "antmicroTestPoints:TP_1.5mm_SMD")
		(at 276.86 177.8 0)
		(unit 1)
		(exclude_from_sim no)
		(in_bom no)
		(on_board yes)
		(dnp no)
		(property "Reference" "TP7"
			(at 276.86 176.53 0)
			(effects
				(font
					(size 1.27 1.27)
					(thickness 0.15)
				)
				(justify right)
			)
		)
		(property "Value" "TP_1.5mm_SMD"
			(at 292.1 185.42 0)
			(effects
				(font
					(size 1.27 1.27)
					(thickness 0.15)
				)
				(justify left bottom)
				(hide yes)
			)
		)
		(property "Footprint" "antmicro-footprints:TP_SMD_1.5mm"
			(at 292.1 187.96 0)
			(effects
				(font
					(size 1.27 1.27)
					(thickness 0.15)
				)
				(justify left bottom)
				(hide yes)
			)
		)
		(property "Datasheet" ""
			(at 294.64 190.5 0)
			(effects
				(font
					(size 1.27 1.27)
					(thickness 0.15)
				)
				(justify left bottom)
				(hide yes)
			)
		)
		(property "Description" ""
			(at 276.86 177.8 0)
			(effects
				(font
					(size 1.27 1.27)
				)
				(hide yes)
			)
		)
		(property "MPN" ""
			(at 276.86 177.8 0)
			(effects
				(font
					(size 1.27 1.27)
				)
				(hide yes)
			)
		)
		(property "Manufacturer" ""
			(at 276.86 177.8 0)
			(effects
				(font
					(size 1.27 1.27)
				)
				(hide yes)
			)
		)
		(property "Author" "Antmicro"
			(at 292.1 193.04 0)
			(effects
				(font
					(size 1.27 1.27)
					(thickness 0.15)
				)
				(justify left bottom)
				(hide yes)
			)
		)
		(property "License" "Apache-2.0"
			(at 292.1 195.58 0)
			(effects
				(font
					(size 1.27 1.27)
					(thickness 0.15)
				)
				(justify left bottom)
				(hide yes)
			)
		)
		(pin "1"
		)
		(instances
			(project "gmsl-serializer"
				(path ""
					(reference "TP7")
					(unit 1)
				)
			)
		)
	)
	(symbol
		(lib_id "antmicroTestPoints:TP_1.5mm_SMD")
		(at 276.86 180.34 0)
		(unit 1)
		(exclude_from_sim no)
		(in_bom no)
		(on_board yes)
		(dnp no)
		(property "Reference" "TP8"
			(at 276.86 179.07 0)
			(effects
				(font
					(size 1.27 1.27)
					(thickness 0.15)
				)
				(justify right)
			)
		)
		(property "Value" "TP_1.5mm_SMD"
			(at 292.1 187.96 0)
			(effects
				(font
					(size 1.27 1.27)
					(thickness 0.15)
				)
				(justify left bottom)
				(hide yes)
			)
		)
		(property "Footprint" "antmicro-footprints:TP_SMD_1.5mm"
			(at 292.1 190.5 0)
			(effects
				(font
					(size 1.27 1.27)
					(thickness 0.15)
				)
				(justify left bottom)
				(hide yes)
			)
		)
		(property "Datasheet" ""
			(at 294.64 193.04 0)
			(effects
				(font
					(size 1.27 1.27)
					(thickness 0.15)
				)
				(justify left bottom)
				(hide yes)
			)
		)
		(property "Description" ""
			(at 276.86 180.34 0)
			(effects
				(font
					(size 1.27 1.27)
				)
				(hide yes)
			)
		)
		(property "MPN" ""
			(at 276.86 180.34 0)
			(effects
				(font
					(size 1.27 1.27)
				)
				(hide yes)
			)
		)
		(property "Manufacturer" ""
			(at 276.86 180.34 0)
			(effects
				(font
					(size 1.27 1.27)
				)
				(hide yes)
			)
		)
		(property "Author" "Antmicro"
			(at 292.1 195.58 0)
			(effects
				(font
					(size 1.27 1.27)
					(thickness 0.15)
				)
				(justify left bottom)
				(hide yes)
			)
		)
		(property "License" "Apache-2.0"
			(at 292.1 198.12 0)
			(effects
				(font
					(size 1.27 1.27)
					(thickness 0.15)
				)
				(justify left bottom)
				(hide yes)
			)
		)
		(pin "1"
		)
		(instances
			(project "gmsl-serializer"
				(path ""
					(reference "TP8")
					(unit 1)
				)
			)
		)
	)
	(symbol
		(lib_id "antmicropower:+3V3")
		(at 234.95 165.1 0)
		(mirror y)
		(unit 1)
		(exclude_from_sim no)
		(in_bom yes)
		(on_board yes)
		(dnp no)
		(property "Reference" "#PWR011"
			(at 219.71 167.64 0)
			(effects
				(font
					(size 1.27 1.27)
					(thickness 0.15)
				)
				(justify left bottom)
				(hide yes)
			)
		)
		(property "Value" "+3V3"
			(at 234.95 161.29 0)
			(effects
				(font
					(size 1.27 1.27)
					(thickness 0.15)
				)
			)
		)
		(property "Footprint" ""
			(at 219.71 172.72 0)
			(effects
				(font
					(size 1.27 1.27)
					(thickness 0.15)
				)
				(justify left bottom)
				(hide yes)
			)
		)
		(property "Datasheet" ""
			(at 219.71 175.26 0)
			(effects
				(font
					(size 1.27 1.27)
					(thickness 0.15)
				)
				(justify left bottom)
				(hide yes)
			)
		)
		(property "Description" ""
			(at 234.95 165.1 0)
			(effects
				(font
					(size 1.27 1.27)
				)
				(hide yes)
			)
		)
		(property "Author" "Antmicro"
			(at 219.71 172.72 0)
			(effects
				(font
					(size 1.27 1.27)
					(thickness 0.15)
				)
				(justify left bottom)
				(hide yes)
			)
		)
		(property "License" "Apache-2.0"
			(at 219.71 175.26 0)
			(effects
				(font
					(size 1.27 1.27)
					(thickness 0.15)
				)
				(justify left bottom)
				(hide yes)
			)
		)
		(pin "1"
		)
		(instances
			(project "gmsl-serializer"
				(path ""
					(reference "#PWR011")
					(unit 1)
				)
			)
		)
	)
	(symbol
		(lib_id "antmicroCapacitors0402:C_100n_0402")
		(at 231.14 154.94 180)
		(unit 1)
		(exclude_from_sim no)
		(in_bom yes)
		(on_board yes)
		(dnp no)
		(property "Reference" "C30"
			(at 231.14 153.035 0)
			(effects
				(font
					(size 1.27 1.27)
					(thickness 0.15)
				)
			)
		)
		(property "Value" "C_100n_0402"
			(at 210.82 144.78 0)
			(effects
				(font
					(size 1.27 1.27)
					(thickness 0.15)
				)
				(justify left bottom)
				(hide yes)
			)
		)
		(property "Footprint" "antmicro-footprints:C_0402_1005Metric"
			(at 210.82 142.24 0)
			(effects
				(font
					(size 1.27 1.27)
					(thickness 0.15)
				)
				(justify left bottom)
				(hide yes)
			)
		)
		(property "Datasheet" "https://www.murata.com/products/productdetail?partno=GRM155R61H104KE14%23"
			(at 210.82 139.7 0)
			(effects
				(font
					(size 1.27 1.27)
					(thickness 0.15)
				)
				(justify left bottom)
				(hide yes)
			)
		)
		(property "Description" ""
			(at 231.14 154.94 0)
			(effects
				(font
					(size 1.27 1.27)
				)
				(hide yes)
			)
		)
		(property "MPN" "GRM155R61H104KE14D"
			(at 210.82 137.16 0)
			(effects
				(font
					(size 1.27 1.27)
					(thickness 0.15)
				)
				(justify left bottom)
				(hide yes)
			)
		)
		(property "Manufacturer" "Murata"
			(at 210.82 134.62 0)
			(effects
				(font
					(size 1.27 1.27)
					(thickness 0.15)
				)
				(justify left bottom)
				(hide yes)
			)
		)
		(property "License" "Apache-2.0"
			(at 210.82 132.08 0)
			(effects
				(font
					(size 1.27 1.27)
					(thickness 0.15)
				)
				(justify left bottom)
				(hide yes)
			)
		)
		(property "Author" "Antmicro"
			(at 210.82 129.54 0)
			(effects
				(font
					(size 1.27 1.27)
					(thickness 0.15)
				)
				(justify left bottom)
				(hide yes)
			)
		)
		(property "Val" "100n"
			(at 224.79 153.035 0)
			(effects
				(font
					(size 1.27 1.27)
					(thickness 0.15)
				)
			)
		)
		(property "Voltage" "50V"
			(at 210.82 127 0)
			(effects
				(font
					(size 1.27 1.27)
				)
				(justify left bottom)
				(hide yes)
			)
		)
		(property "Dielectric" "X5R"
			(at 210.82 124.46 0)
			(effects
				(font
					(size 1.27 1.27)
				)
				(justify left bottom)
				(hide yes)
			)
		)
		(pin "1"
		)
		(pin "2"
		)
		(instances
			(project "gmsl-serializer"
				(path ""
					(reference "C30")
					(unit 1)
				)
			)
		)
	)
	(symbol
		(lib_id "antmicropower:+3V3")
		(at 45.72 195.58 0)
		(unit 1)
		(exclude_from_sim no)
		(in_bom yes)
		(on_board yes)
		(dnp no)
		(property "Reference" "#PWR0156"
			(at 60.96 198.12 0)
			(effects
				(font
					(size 1.27 1.27)
					(thickness 0.15)
				)
				(justify left bottom)
				(hide yes)
			)
		)
		(property "Value" "+3V3"
			(at 45.72 191.77 0)
			(effects
				(font
					(size 1.27 1.27)
					(thickness 0.15)
				)
			)
		)
		(property "Footprint" ""
			(at 60.96 203.2 0)
			(effects
				(font
					(size 1.27 1.27)
					(thickness 0.15)
				)
				(justify left bottom)
				(hide yes)
			)
		)
		(property "Datasheet" ""
			(at 60.96 205.74 0)
			(effects
				(font
					(size 1.27 1.27)
					(thickness 0.15)
				)
				(justify left bottom)
				(hide yes)
			)
		)
		(property "Description" ""
			(at 45.72 195.58 0)
			(effects
				(font
					(size 1.27 1.27)
				)
				(hide yes)
			)
		)
		(property "Author" "Antmicro"
			(at 60.96 203.2 0)
			(effects
				(font
					(size 1.27 1.27)
					(thickness 0.15)
				)
				(justify left bottom)
				(hide yes)
			)
		)
		(property "License" "Apache-2.0"
			(at 60.96 205.74 0)
			(effects
				(font
					(size 1.27 1.27)
					(thickness 0.15)
				)
				(justify left bottom)
				(hide yes)
			)
		)
		(pin "1"
		)
		(instances
			(project "gmsl-serializer"
				(path ""
					(reference "#PWR0156")
					(unit 1)
				)
			)
		)
	)
	(symbol
		(lib_id "antmicroCapacitors0402:C_10u_0402")
		(at 215.9 119.38 90)
		(unit 1)
		(exclude_from_sim no)
		(in_bom yes)
		(on_board yes)
		(dnp no)
		(property "Reference" "C25"
			(at 217.17 115.57 90)
			(effects
				(font
					(size 1.27 1.27)
					(thickness 0.15)
				)
				(justify right)
			)
		)
		(property "Value" "C_10u_0402"
			(at 226.06 99.06 0)
			(effects
				(font
					(size 1.27 1.27)
					(thickness 0.15)
				)
				(justify left bottom)
				(hide yes)
			)
		)
		(property "Footprint" "antmicro-footprints:C_0402_1005Metric"
			(at 228.6 99.06 0)
			(effects
				(font
					(size 1.27 1.27)
					(thickness 0.15)
				)
				(justify left bottom)
				(hide yes)
			)
		)
		(property "Datasheet" "https://www.yageo.com/en/Chart/Download/pdf/CC0402MRX5R5BB106"
			(at 231.14 99.06 0)
			(effects
				(font
					(size 1.27 1.27)
					(thickness 0.15)
				)
				(justify left bottom)
				(hide yes)
			)
		)
		(property "Description" ""
			(at 215.9 119.38 0)
			(effects
				(font
					(size 1.27 1.27)
				)
				(hide yes)
			)
		)
		(property "MPN" "CC0402MRX5R5BB106"
			(at 233.68 99.06 0)
			(effects
				(font
					(size 1.27 1.27)
					(thickness 0.15)
				)
				(justify left bottom)
				(hide yes)
			)
		)
		(property "Manufacturer" "YAGEO"
			(at 236.22 99.06 0)
			(effects
				(font
					(size 1.27 1.27)
					(thickness 0.15)
				)
				(justify left bottom)
				(hide yes)
			)
		)
		(property "License" "Apache-2.0"
			(at 238.76 99.06 0)
			(effects
				(font
					(size 1.27 1.27)
					(thickness 0.15)
				)
				(justify left bottom)
				(hide yes)
			)
		)
		(property "Author" "Antmicro"
			(at 241.3 99.06 0)
			(effects
				(font
					(size 1.27 1.27)
					(thickness 0.15)
				)
				(justify left bottom)
				(hide yes)
			)
		)
		(property "Val" "10u"
			(at 217.17 118.11 90)
			(effects
				(font
					(size 1.27 1.27)
					(thickness 0.15)
				)
				(justify right)
			)
		)
		(property "Voltage" ""
			(at 243.84 99.06 0)
			(effects
				(font
					(size 1.27 1.27)
				)
				(justify left bottom)
				(hide yes)
			)
		)
		(property "Dielectric" ""
			(at 246.38 99.06 0)
			(effects
				(font
					(size 1.27 1.27)
				)
				(justify left bottom)
				(hide yes)
			)
		)
		(pin "1"
		)
		(pin "2"
		)
		(instances
			(project "gmsl-serializer"
				(path ""
					(reference "C25")
					(unit 1)
				)
			)
		)
	)
	(symbol
		(lib_id "antmicropower:GND")
		(at 227.33 185.42 0)
		(mirror y)
		(unit 1)
		(exclude_from_sim no)
		(in_bom yes)
		(on_board yes)
		(dnp no)
		(property "Reference" "#PWR0152"
			(at 218.44 187.96 0)
			(effects
				(font
					(size 1.27 1.27)
					(thickness 0.15)
				)
				(justify left bottom)
				(hide yes)
			)
		)
		(property "Value" "GND"
			(at 227.33 189.23 0)
			(effects
				(font
					(size 1.27 1.27)
					(thickness 0.15)
				)
			)
		)
		(property "Footprint" ""
			(at 218.44 193.04 0)
			(effects
				(font
					(size 1.27 1.27)
					(thickness 0.15)
				)
				(justify left bottom)
				(hide yes)
			)
		)
		(property "Datasheet" ""
			(at 218.44 198.12 0)
			(effects
				(font
					(size 1.27 1.27)
					(thickness 0.15)
				)
				(justify left bottom)
				(hide yes)
			)
		)
		(property "Description" ""
			(at 227.33 185.42 0)
			(effects
				(font
					(size 1.27 1.27)
				)
				(hide yes)
			)
		)
		(property "Author" "Antmicro"
			(at 218.44 193.04 0)
			(effects
				(font
					(size 1.27 1.27)
					(thickness 0.15)
				)
				(justify left bottom)
				(hide yes)
			)
		)
		(property "License" "Apache-2.0"
			(at 218.44 195.58 0)
			(effects
				(font
					(size 1.27 1.27)
					(thickness 0.15)
				)
				(justify left bottom)
				(hide yes)
			)
		)
		(pin "1"
		)
		(instances
			(project "gmsl-serializer"
				(path ""
					(reference "#PWR0152")
					(unit 1)
				)
			)
		)
	)
	(symbol
		(lib_id "antmicroResistors0402:R_80k6_0402")
		(at 45.72 201.93 90)
		(unit 1)
		(exclude_from_sim no)
		(in_bom no)
		(on_board yes)
		(dnp yes)
		(property "Reference" "R18"
			(at 47.625 198.12 90)
			(effects
				(font
					(size 1.27 1.27)
					(thickness 0.15)
				)
				(justify right)
			)
		)
		(property "Value" "R_80k6_0402"
			(at 58.42 181.61 0)
			(effects
				(font
					(size 1.27 1.27)
					(thickness 0.15)
				)
				(justify left bottom)
				(hide yes)
			)
		)
		(property "Footprint" "antmicro-footprints:R_0402_1005Metric"
			(at 60.96 181.61 0)
			(effects
				(font
					(size 1.27 1.27)
					(thickness 0.15)
				)
				(justify left bottom)
				(hide yes)
			)
		)
		(property "Datasheet" "https://www.bourns.com/docs/product-datasheets/cr.pdf"
			(at 63.5 181.61 0)
			(effects
				(font
					(size 1.27 1.27)
					(thickness 0.15)
				)
				(justify left bottom)
				(hide yes)
			)
		)
		(property "Description" ""
			(at 45.72 201.93 0)
			(effects
				(font
					(size 1.27 1.27)
				)
				(hide yes)
			)
		)
		(property "MPN" "CR0402-FX-8062GLF"
			(at 66.04 181.61 0)
			(effects
				(font
					(size 1.27 1.27)
					(thickness 0.15)
				)
				(justify left bottom)
				(hide yes)
			)
		)
		(property "Manufacturer" "Bourns"
			(at 68.58 181.61 0)
			(effects
				(font
					(size 1.27 1.27)
					(thickness 0.15)
				)
				(justify left bottom)
				(hide yes)
			)
		)
		(property "License" "Apache-2.0"
			(at 71.12 181.61 0)
			(effects
				(font
					(size 1.27 1.27)
					(thickness 0.15)
				)
				(justify left bottom)
				(hide yes)
			)
		)
		(property "Author" "Antmicro"
			(at 73.66 181.61 0)
			(effects
				(font
					(size 1.27 1.27)
					(thickness 0.15)
				)
				(justify left bottom)
				(hide yes)
			)
		)
		(property "Val" "80k6"
			(at 47.625 200.66 90)
			(effects
				(font
					(size 1.27 1.27)
					(thickness 0.15)
				)
				(justify right)
			)
		)
		(property "Tolerance" "1%"
			(at 55.88 181.61 0)
			(effects
				(font
					(size 1.27 1.27)
				)
				(justify left bottom)
				(hide yes)
			)
		)
		(pin "1"
		)
		(pin "2"
		)
		(instances
			(project "gmsl-serializer"
				(path ""
					(reference "R18")
					(unit 1)
				)
			)
		)
	)
	(symbol
		(lib_id "antmicroInterfaceControllers:MAX96717GTJ_VY+")
		(at 243.84 137.16 0)
		(unit 1)
		(exclude_from_sim no)
		(in_bom yes)
		(on_board yes)
		(dnp no)
		(fields_autoplaced yes)
		(property "Reference" "U6"
			(at 257.81 129.54 0)
			(effects
				(font
					(size 1.27 1.27)
					(thickness 0.15)
				)
			)
		)
		(property "Value" "MAX96717GTJ_VY+"
			(at 292.1 142.24 0)
			(effects
				(font
					(size 1.27 1.27)
				)
				(justify left bottom)
				(hide yes)
			)
		)
		(property "Footprint" "antmicro-footprints:TQFN-32-1EP_5x5mm_P0.5mm"
			(at 292.1 144.78 0)
			(effects
				(font
					(size 1.27 1.27)
				)
				(justify left bottom)
				(hide yes)
			)
		)
		(property "Datasheet" "https://www.analog.com/media/en/technical-documentation/data-sheets/max96717.pdf"
			(at 292.1 147.32 0)
			(effects
				(font
					(size 1.27 1.27)
				)
				(justify left bottom)
				(hide yes)
			)
		)
		(property "Description" ""
			(at 243.84 137.16 0)
			(effects
				(font
					(size 1.27 1.27)
				)
				(hide yes)
			)
		)
		(property "MPN" "MAX96717GTJ/VY+"
			(at 257.81 132.08 0)
			(effects
				(font
					(size 1.27 1.27)
				)
			)
		)
		(property "Manufacturer" "Analog Devices"
			(at 292.1 152.4 0)
			(effects
				(font
					(size 1.27 1.27)
				)
				(justify left bottom)
				(hide yes)
			)
		)
		(property "Author" "Antmicro"
			(at 292.1 154.94 0)
			(effects
				(font
					(size 1.27 1.27)
				)
				(justify left bottom)
				(hide yes)
			)
		)
		(property "License" "Apache-2.0"
			(at 292.1 157.48 0)
			(effects
				(font
					(size 1.27 1.27)
				)
				(justify left bottom)
				(hide yes)
			)
		)
		(pin "1"
		)
		(pin "10"
		)
		(pin "11"
		)
		(pin "12"
		)
		(pin "13"
		)
		(pin "14"
		)
		(pin "15"
		)
		(pin "16"
		)
		(pin "17"
		)
		(pin "18"
		)
		(pin "19"
		)
		(pin "2"
		)
		(pin "20"
		)
		(pin "21"
		)
		(pin "22"
		)
		(pin "23"
		)
		(pin "24"
		)
		(pin "25"
		)
		(pin "26"
		)
		(pin "27"
		)
		(pin "28"
		)
		(pin "29"
		)
		(pin "3"
		)
		(pin "30"
		)
		(pin "31"
		)
		(pin "32"
		)
		(pin "33"
		)
		(pin "4"
		)
		(pin "5"
		)
		(pin "6"
		)
		(pin "7"
		)
		(pin "8"
		)
		(pin "9"
		)
		(instances
			(project "gmsl-serializer"
				(path ""
					(reference "U6")
					(unit 1)
				)
			)
		)
	)
	(symbol
		(lib_id "antmicropower:GND")
		(at 215.9 121.92 0)
		(unit 1)
		(exclude_from_sim no)
		(in_bom yes)
		(on_board yes)
		(dnp no)
		(property "Reference" "#PWR0143"
			(at 224.79 124.46 0)
			(effects
				(font
					(size 1.27 1.27)
					(thickness 0.15)
				)
				(justify left bottom)
				(hide yes)
			)
		)
		(property "Value" "GND"
			(at 215.9 125.73 0)
			(effects
				(font
					(size 1.27 1.27)
					(thickness 0.15)
				)
			)
		)
		(property "Footprint" ""
			(at 224.79 129.54 0)
			(effects
				(font
					(size 1.27 1.27)
					(thickness 0.15)
				)
				(justify left bottom)
				(hide yes)
			)
		)
		(property "Datasheet" ""
			(at 224.79 134.62 0)
			(effects
				(font
					(size 1.27 1.27)
					(thickness 0.15)
				)
				(justify left bottom)
				(hide yes)
			)
		)
		(property "Description" ""
			(at 215.9 121.92 0)
			(effects
				(font
					(size 1.27 1.27)
				)
				(hide yes)
			)
		)
		(property "Author" "Antmicro"
			(at 224.79 129.54 0)
			(effects
				(font
					(size 1.27 1.27)
					(thickness 0.15)
				)
				(justify left bottom)
				(hide yes)
			)
		)
		(property "License" "Apache-2.0"
			(at 224.79 132.08 0)
			(effects
				(font
					(size 1.27 1.27)
					(thickness 0.15)
				)
				(justify left bottom)
				(hide yes)
			)
		)
		(pin "1"
		)
		(instances
			(project "gmsl-serializer"
				(path ""
					(reference "#PWR0143")
					(unit 1)
				)
			)
		)
	)
	(symbol
		(lib_id "antmicropower:GND")
		(at 240.03 185.42 0)
		(mirror y)
		(unit 1)
		(exclude_from_sim no)
		(in_bom yes)
		(on_board yes)
		(dnp no)
		(property "Reference" "#PWR0150"
			(at 231.14 187.96 0)
			(effects
				(font
					(size 1.27 1.27)
					(thickness 0.15)
				)
				(justify left bottom)
				(hide yes)
			)
		)
		(property "Value" "GND"
			(at 240.03 189.23 0)
			(effects
				(font
					(size 1.27 1.27)
					(thickness 0.15)
				)
			)
		)
		(property "Footprint" ""
			(at 231.14 193.04 0)
			(effects
				(font
					(size 1.27 1.27)
					(thickness 0.15)
				)
				(justify left bottom)
				(hide yes)
			)
		)
		(property "Datasheet" ""
			(at 231.14 198.12 0)
			(effects
				(font
					(size 1.27 1.27)
					(thickness 0.15)
				)
				(justify left bottom)
				(hide yes)
			)
		)
		(property "Description" ""
			(at 240.03 185.42 0)
			(effects
				(font
					(size 1.27 1.27)
				)
				(hide yes)
			)
		)
		(property "Author" "Antmicro"
			(at 231.14 193.04 0)
			(effects
				(font
					(size 1.27 1.27)
					(thickness 0.15)
				)
				(justify left bottom)
				(hide yes)
			)
		)
		(property "License" "Apache-2.0"
			(at 231.14 195.58 0)
			(effects
				(font
					(size 1.27 1.27)
					(thickness 0.15)
				)
				(justify left bottom)
				(hide yes)
			)
		)
		(pin "1"
		)
		(instances
			(project "gmsl-serializer"
				(path ""
					(reference "#PWR0150")
					(unit 1)
				)
			)
		)
	)
	(symbol
		(lib_id "antmicropower:GND")
		(at 57.15 110.49 0)
		(unit 1)
		(exclude_from_sim no)
		(in_bom yes)
		(on_board yes)
		(dnp no)
		(property "Reference" "#PWR0149"
			(at 66.04 113.03 0)
			(effects
				(font
					(size 1.27 1.27)
					(thickness 0.15)
				)
				(justify left bottom)
				(hide yes)
			)
		)
		(property "Value" "GND"
			(at 57.15 114.3 0)
			(effects
				(font
					(size 1.27 1.27)
					(thickness 0.15)
				)
			)
		)
		(property "Footprint" ""
			(at 66.04 118.11 0)
			(effects
				(font
					(size 1.27 1.27)
					(thickness 0.15)
				)
				(justify left bottom)
				(hide yes)
			)
		)
		(property "Datasheet" ""
			(at 66.04 123.19 0)
			(effects
				(font
					(size 1.27 1.27)
					(thickness 0.15)
				)
				(justify left bottom)
				(hide yes)
			)
		)
		(property "Description" ""
			(at 57.15 110.49 0)
			(effects
				(font
					(size 1.27 1.27)
				)
				(hide yes)
			)
		)
		(property "Author" "Antmicro"
			(at 66.04 118.11 0)
			(effects
				(font
					(size 1.27 1.27)
					(thickness 0.15)
				)
				(justify left bottom)
				(hide yes)
			)
		)
		(property "License" "Apache-2.0"
			(at 66.04 120.65 0)
			(effects
				(font
					(size 1.27 1.27)
					(thickness 0.15)
				)
				(justify left bottom)
				(hide yes)
			)
		)
		(pin "1"
		)
		(instances
			(project "gmsl-serializer"
				(path ""
					(reference "#PWR0149")
					(unit 1)
				)
			)
		)
	)
	(symbol
		(lib_id "antmicropower:GND")
		(at 222.25 166.37 0)
		(unit 1)
		(exclude_from_sim no)
		(in_bom yes)
		(on_board yes)
		(dnp no)
		(property "Reference" "#PWR0141"
			(at 231.14 168.91 0)
			(effects
				(font
					(size 1.27 1.27)
					(thickness 0.15)
				)
				(justify left bottom)
				(hide yes)
			)
		)
		(property "Value" "GND"
			(at 222.25 170.18 0)
			(effects
				(font
					(size 1.27 1.27)
					(thickness 0.15)
				)
			)
		)
		(property "Footprint" ""
			(at 231.14 173.99 0)
			(effects
				(font
					(size 1.27 1.27)
					(thickness 0.15)
				)
				(justify left bottom)
				(hide yes)
			)
		)
		(property "Datasheet" ""
			(at 231.14 179.07 0)
			(effects
				(font
					(size 1.27 1.27)
					(thickness 0.15)
				)
				(justify left bottom)
				(hide yes)
			)
		)
		(property "Description" ""
			(at 222.25 166.37 0)
			(effects
				(font
					(size 1.27 1.27)
				)
				(hide yes)
			)
		)
		(property "Author" "Antmicro"
			(at 231.14 173.99 0)
			(effects
				(font
					(size 1.27 1.27)
					(thickness 0.15)
				)
				(justify left bottom)
				(hide yes)
			)
		)
		(property "License" "Apache-2.0"
			(at 231.14 176.53 0)
			(effects
				(font
					(size 1.27 1.27)
					(thickness 0.15)
				)
				(justify left bottom)
				(hide yes)
			)
		)
		(pin "1"
		)
		(instances
			(project "gmsl-serializer"
				(path ""
					(reference "#PWR0141")
					(unit 1)
				)
			)
		)
	)
	(symbol
		(lib_id "antmicropower:GND")
		(at 45.72 213.36 0)
		(unit 1)
		(exclude_from_sim no)
		(in_bom yes)
		(on_board yes)
		(dnp no)
		(property "Reference" "#PWR0148"
			(at 54.61 215.9 0)
			(effects
				(font
					(size 1.27 1.27)
					(thickness 0.15)
				)
				(justify left bottom)
				(hide yes)
			)
		)
		(property "Value" "GND"
			(at 45.72 217.17 0)
			(effects
				(font
					(size 1.27 1.27)
					(thickness 0.15)
				)
			)
		)
		(property "Footprint" ""
			(at 54.61 220.98 0)
			(effects
				(font
					(size 1.27 1.27)
					(thickness 0.15)
				)
				(justify left bottom)
				(hide yes)
			)
		)
		(property "Datasheet" ""
			(at 54.61 226.06 0)
			(effects
				(font
					(size 1.27 1.27)
					(thickness 0.15)
				)
				(justify left bottom)
				(hide yes)
			)
		)
		(property "Description" ""
			(at 45.72 213.36 0)
			(effects
				(font
					(size 1.27 1.27)
				)
				(hide yes)
			)
		)
		(property "Author" "Antmicro"
			(at 54.61 220.98 0)
			(effects
				(font
					(size 1.27 1.27)
					(thickness 0.15)
				)
				(justify left bottom)
				(hide yes)
			)
		)
		(property "License" "Apache-2.0"
			(at 54.61 223.52 0)
			(effects
				(font
					(size 1.27 1.27)
					(thickness 0.15)
				)
				(justify left bottom)
				(hide yes)
			)
		)
		(pin "1"
		)
		(instances
			(project "gmsl-serializer"
				(path ""
					(reference "#PWR0148")
					(unit 1)
				)
			)
		)
	)
	(symbol
		(lib_id "antmicropower:GND")
		(at 242.57 193.04 0)
		(mirror y)
		(unit 1)
		(exclude_from_sim no)
		(in_bom yes)
		(on_board yes)
		(dnp no)
		(property "Reference" "#PWR0154"
			(at 233.68 195.58 0)
			(effects
				(font
					(size 1.27 1.27)
					(thickness 0.15)
				)
				(justify left bottom)
				(hide yes)
			)
		)
		(property "Value" "GND"
			(at 242.57 196.85 0)
			(effects
				(font
					(size 1.27 1.27)
					(thickness 0.15)
				)
			)
		)
		(property "Footprint" ""
			(at 233.68 200.66 0)
			(effects
				(font
					(size 1.27 1.27)
					(thickness 0.15)
				)
				(justify left bottom)
				(hide yes)
			)
		)
		(property "Datasheet" ""
			(at 233.68 205.74 0)
			(effects
				(font
					(size 1.27 1.27)
					(thickness 0.15)
				)
				(justify left bottom)
				(hide yes)
			)
		)
		(property "Description" ""
			(at 242.57 193.04 0)
			(effects
				(font
					(size 1.27 1.27)
				)
				(hide yes)
			)
		)
		(property "Author" "Antmicro"
			(at 233.68 200.66 0)
			(effects
				(font
					(size 1.27 1.27)
					(thickness 0.15)
				)
				(justify left bottom)
				(hide yes)
			)
		)
		(property "License" "Apache-2.0"
			(at 233.68 203.2 0)
			(effects
				(font
					(size 1.27 1.27)
					(thickness 0.15)
				)
				(justify left bottom)
				(hide yes)
			)
		)
		(pin "1"
		)
		(instances
			(project "gmsl-serializer"
				(path ""
					(reference "#PWR0154")
					(unit 1)
				)
			)
		)
	)
	(symbol
		(lib_id "antmicroCapacitors0402:C_10n_0402")
		(at 231.14 119.38 90)
		(unit 1)
		(exclude_from_sim no)
		(in_bom yes)
		(on_board yes)
		(dnp no)
		(property "Reference" "C28"
			(at 232.41 115.57 90)
			(effects
				(font
					(size 1.27 1.27)
					(thickness 0.15)
				)
				(justify right)
			)
		)
		(property "Value" "C_10n_0402"
			(at 241.3 99.06 0)
			(effects
				(font
					(size 1.27 1.27)
					(thickness 0.15)
				)
				(justify left bottom)
				(hide yes)
			)
		)
		(property "Footprint" "antmicro-footprints:C_0402_1005Metric"
			(at 243.84 99.06 0)
			(effects
				(font
					(size 1.27 1.27)
					(thickness 0.15)
				)
				(justify left bottom)
				(hide yes)
			)
		)
		(property "Datasheet" "https://www.murata.com/products/productdetail?partno=GRM155R71H103KA88%23"
			(at 246.38 99.06 0)
			(effects
				(font
					(size 1.27 1.27)
					(thickness 0.15)
				)
				(justify left bottom)
				(hide yes)
			)
		)
		(property "Description" ""
			(at 231.14 119.38 0)
			(effects
				(font
					(size 1.27 1.27)
				)
				(hide yes)
			)
		)
		(property "MPN" "GRM155R71H103KA88D"
			(at 248.92 99.06 0)
			(effects
				(font
					(size 1.27 1.27)
					(thickness 0.15)
				)
				(justify left bottom)
				(hide yes)
			)
		)
		(property "Manufacturer" "Murata"
			(at 251.46 99.06 0)
			(effects
				(font
					(size 1.27 1.27)
					(thickness 0.15)
				)
				(justify left bottom)
				(hide yes)
			)
		)
		(property "License" "Apache-2.0"
			(at 254 99.06 0)
			(effects
				(font
					(size 1.27 1.27)
					(thickness 0.15)
				)
				(justify left bottom)
				(hide yes)
			)
		)
		(property "Author" "Antmicro"
			(at 256.54 99.06 0)
			(effects
				(font
					(size 1.27 1.27)
					(thickness 0.15)
				)
				(justify left bottom)
				(hide yes)
			)
		)
		(property "Val" "10n"
			(at 232.41 118.11 90)
			(effects
				(font
					(size 1.27 1.27)
					(thickness 0.15)
				)
				(justify right)
			)
		)
		(property "Voltage" "50V"
			(at 259.08 99.06 0)
			(effects
				(font
					(size 1.27 1.27)
				)
				(justify left bottom)
				(hide yes)
			)
		)
		(property "Dielectric" "X7R"
			(at 261.62 99.06 0)
			(effects
				(font
					(size 1.27 1.27)
				)
				(justify left bottom)
				(hide yes)
			)
		)
		(pin "1"
		)
		(pin "2"
		)
		(instances
			(project "gmsl-serializer"
				(path ""
					(reference "C28")
					(unit 1)
				)
			)
		)
	)
	(symbol
		(lib_id "antmicroResistors0402:R_0R_0402")
		(at 290.83 187.96 0)
		(mirror y)
		(unit 1)
		(exclude_from_sim no)
		(in_bom yes)
		(on_board yes)
		(dnp no)
		(property "Reference" "R32"
			(at 285.75 186.69 0)
			(effects
				(font
					(size 1.27 1.27)
					(thickness 0.15)
				)
				(justify left)
			)
		)
		(property "Value" "R_0R_0402"
			(at 270.51 200.66 0)
			(effects
				(font
					(size 1.27 1.27)
					(thickness 0.15)
				)
				(justify left bottom)
				(hide yes)
			)
		)
		(property "Footprint" "antmicro-footprints:R_0402_1005Metric"
			(at 270.51 203.2 0)
			(effects
				(font
					(size 1.27 1.27)
					(thickness 0.15)
				)
				(justify left bottom)
				(hide yes)
			)
		)
		(property "Datasheet" "https://industrial.panasonic.com/cdbs/www-data/pdf/RDA0000/AOA0000C301.pdf"
			(at 270.51 205.74 0)
			(effects
				(font
					(size 1.27 1.27)
					(thickness 0.15)
				)
				(justify left bottom)
				(hide yes)
			)
		)
		(property "Description" ""
			(at 290.83 187.96 0)
			(effects
				(font
					(size 1.27 1.27)
				)
				(hide yes)
			)
		)
		(property "MPN" "ERJ2GE0R00X"
			(at 270.51 208.28 0)
			(effects
				(font
					(size 1.27 1.27)
					(thickness 0.15)
				)
				(justify left bottom)
				(hide yes)
			)
		)
		(property "Manufacturer" "Panasonic"
			(at 270.51 210.82 0)
			(effects
				(font
					(size 1.27 1.27)
					(thickness 0.15)
				)
				(justify left bottom)
				(hide yes)
			)
		)
		(property "License" "Apache-2.0"
			(at 270.51 213.36 0)
			(effects
				(font
					(size 1.27 1.27)
					(thickness 0.15)
				)
				(justify left bottom)
				(hide yes)
			)
		)
		(property "Author" "Antmicro"
			(at 270.51 215.9 0)
			(effects
				(font
					(size 1.27 1.27)
					(thickness 0.15)
				)
				(justify left bottom)
				(hide yes)
			)
		)
		(property "Val" "0R"
			(at 292.1 186.69 0)
			(effects
				(font
					(size 1.27 1.27)
					(thickness 0.15)
				)
			)
		)
		(property "Tolerance" "~"
			(at 270.51 198.12 0)
			(effects
				(font
					(size 1.27 1.27)
				)
				(justify left bottom)
				(hide yes)
			)
		)
		(property "Current" "1A"
			(at 270.51 218.44 0)
			(effects
				(font
					(size 1.27 1.27)
					(thickness 0.15)
				)
				(justify left bottom)
				(hide yes)
			)
		)
		(pin "1"
		)
		(pin "2"
		)
		(instances
			(project "gmsl-serializer"
				(path ""
					(reference "R32")
					(unit 1)
				)
			)
		)
	)
	(symbol
		(lib_id "antmicroCapacitors0402:C_10n_0402")
		(at 231.14 139.7 90)
		(unit 1)
		(exclude_from_sim no)
		(in_bom yes)
		(on_board yes)
		(dnp no)
		(property "Reference" "C29"
			(at 231.775 135.255 90)
			(effects
				(font
					(size 1.27 1.27)
					(thickness 0.15)
				)
				(justify right)
			)
		)
		(property "Value" "C_10n_0402"
			(at 241.3 119.38 0)
			(effects
				(font
					(size 1.27 1.27)
					(thickness 0.15)
				)
				(justify left bottom)
				(hide yes)
			)
		)
		(property "Footprint" "antmicro-footprints:C_0402_1005Metric"
			(at 243.84 119.38 0)
			(effects
				(font
					(size 1.27 1.27)
					(thickness 0.15)
				)
				(justify left bottom)
				(hide yes)
			)
		)
		(property "Datasheet" "https://www.murata.com/products/productdetail?partno=GRM155R71H103KA88%23"
			(at 246.38 119.38 0)
			(effects
				(font
					(size 1.27 1.27)
					(thickness 0.15)
				)
				(justify left bottom)
				(hide yes)
			)
		)
		(property "Description" ""
			(at 231.14 139.7 0)
			(effects
				(font
					(size 1.27 1.27)
				)
				(hide yes)
			)
		)
		(property "MPN" "GRM155R71H103KA88D"
			(at 248.92 119.38 0)
			(effects
				(font
					(size 1.27 1.27)
					(thickness 0.15)
				)
				(justify left bottom)
				(hide yes)
			)
		)
		(property "Manufacturer" "Murata"
			(at 251.46 119.38 0)
			(effects
				(font
					(size 1.27 1.27)
					(thickness 0.15)
				)
				(justify left bottom)
				(hide yes)
			)
		)
		(property "License" "Apache-2.0"
			(at 254 119.38 0)
			(effects
				(font
					(size 1.27 1.27)
					(thickness 0.15)
				)
				(justify left bottom)
				(hide yes)
			)
		)
		(property "Author" "Antmicro"
			(at 256.54 119.38 0)
			(effects
				(font
					(size 1.27 1.27)
					(thickness 0.15)
				)
				(justify left bottom)
				(hide yes)
			)
		)
		(property "Val" "10n"
			(at 231.775 139.065 90)
			(effects
				(font
					(size 1.27 1.27)
					(thickness 0.15)
				)
				(justify right)
			)
		)
		(property "Voltage" "50V"
			(at 259.08 119.38 0)
			(effects
				(font
					(size 1.27 1.27)
				)
				(justify left bottom)
				(hide yes)
			)
		)
		(property "Dielectric" "X7R"
			(at 261.62 119.38 0)
			(effects
				(font
					(size 1.27 1.27)
				)
				(justify left bottom)
				(hide yes)
			)
		)
		(pin "1"
		)
		(pin "2"
		)
		(instances
			(project "gmsl-serializer"
				(path ""
					(reference "C29")
					(unit 1)
				)
			)
		)
	)
	(symbol
		(lib_id "antmicroResistors0402:R_0R_0402")
		(at 290.83 182.88 0)
		(mirror y)
		(unit 1)
		(exclude_from_sim no)
		(in_bom no)
		(on_board yes)
		(dnp yes)
		(property "Reference" "R30"
			(at 285.75 181.61 0)
			(effects
				(font
					(size 1.27 1.27)
					(thickness 0.15)
				)
				(justify left)
			)
		)
		(property "Value" "R_0R_0402"
			(at 270.51 195.58 0)
			(effects
				(font
					(size 1.27 1.27)
					(thickness 0.15)
				)
				(justify left bottom)
				(hide yes)
			)
		)
		(property "Footprint" "antmicro-footprints:R_0402_1005Metric"
			(at 270.51 198.12 0)
			(effects
				(font
					(size 1.27 1.27)
					(thickness 0.15)
				)
				(justify left bottom)
				(hide yes)
			)
		)
		(property "Datasheet" "https://industrial.panasonic.com/cdbs/www-data/pdf/RDA0000/AOA0000C301.pdf"
			(at 270.51 200.66 0)
			(effects
				(font
					(size 1.27 1.27)
					(thickness 0.15)
				)
				(justify left bottom)
				(hide yes)
			)
		)
		(property "Description" ""
			(at 290.83 182.88 0)
			(effects
				(font
					(size 1.27 1.27)
				)
				(hide yes)
			)
		)
		(property "MPN" "ERJ2GE0R00X"
			(at 270.51 203.2 0)
			(effects
				(font
					(size 1.27 1.27)
					(thickness 0.15)
				)
				(justify left bottom)
				(hide yes)
			)
		)
		(property "Manufacturer" "Panasonic"
			(at 270.51 205.74 0)
			(effects
				(font
					(size 1.27 1.27)
					(thickness 0.15)
				)
				(justify left bottom)
				(hide yes)
			)
		)
		(property "License" "Apache-2.0"
			(at 270.51 208.28 0)
			(effects
				(font
					(size 1.27 1.27)
					(thickness 0.15)
				)
				(justify left bottom)
				(hide yes)
			)
		)
		(property "Author" "Antmicro"
			(at 270.51 210.82 0)
			(effects
				(font
					(size 1.27 1.27)
					(thickness 0.15)
				)
				(justify left bottom)
				(hide yes)
			)
		)
		(property "Val" "0R"
			(at 292.1 181.61 0)
			(effects
				(font
					(size 1.27 1.27)
					(thickness 0.15)
				)
			)
		)
		(property "Tolerance" "~"
			(at 270.51 193.04 0)
			(effects
				(font
					(size 1.27 1.27)
				)
				(justify left bottom)
				(hide yes)
			)
		)
		(property "Current" "1A"
			(at 270.51 213.36 0)
			(effects
				(font
					(size 1.27 1.27)
					(thickness 0.15)
				)
				(justify left bottom)
				(hide yes)
			)
		)
		(pin "1"
		)
		(pin "2"
		)
		(instances
			(project "gmsl-serializer"
				(path ""
					(reference "R30")
					(unit 1)
				)
			)
		)
	)
	(symbol
		(lib_id "antmicropower:+3V3")
		(at 215.9 132.08 0)
		(mirror y)
		(unit 1)
		(exclude_from_sim no)
		(in_bom yes)
		(on_board yes)
		(dnp no)
		(property "Reference" "#PWR0139"
			(at 200.66 134.62 0)
			(effects
				(font
					(size 1.27 1.27)
					(thickness 0.15)
				)
				(justify left bottom)
				(hide yes)
			)
		)
		(property "Value" "+3V3"
			(at 215.9 128.27 0)
			(effects
				(font
					(size 1.27 1.27)
					(thickness 0.15)
				)
			)
		)
		(property "Footprint" ""
			(at 200.66 139.7 0)
			(effects
				(font
					(size 1.27 1.27)
					(thickness 0.15)
				)
				(justify left bottom)
				(hide yes)
			)
		)
		(property "Datasheet" ""
			(at 200.66 142.24 0)
			(effects
				(font
					(size 1.27 1.27)
					(thickness 0.15)
				)
				(justify left bottom)
				(hide yes)
			)
		)
		(property "Description" ""
			(at 215.9 132.08 0)
			(effects
				(font
					(size 1.27 1.27)
				)
				(hide yes)
			)
		)
		(property "Author" "Antmicro"
			(at 200.66 139.7 0)
			(effects
				(font
					(size 1.27 1.27)
					(thickness 0.15)
				)
				(justify left bottom)
				(hide yes)
			)
		)
		(property "License" "Apache-2.0"
			(at 200.66 142.24 0)
			(effects
				(font
					(size 1.27 1.27)
					(thickness 0.15)
				)
				(justify left bottom)
				(hide yes)
			)
		)
		(pin "1"
		)
		(instances
			(project "gmsl-serializer"
				(path ""
					(reference "#PWR0139")
					(unit 1)
				)
			)
		)
	)
	(symbol
		(lib_id "antmicroCapacitors0402:C_33p_0402")
		(at 63.5 107.95 90)
		(unit 1)
		(exclude_from_sim no)
		(in_bom yes)
		(on_board yes)
		(dnp no)
		(property "Reference" "C17"
			(at 65.405 103.505 90)
			(effects
				(font
					(size 1.27 1.27)
					(thickness 0.15)
				)
				(justify right)
			)
		)
		(property "Value" "C_33p_0402"
			(at 73.66 87.63 0)
			(effects
				(font
					(size 1.27 1.27)
					(thickness 0.15)
				)
				(justify left bottom)
				(hide yes)
			)
		)
		(property "Footprint" "antmicro-footprints:C_0402_1005Metric"
			(at 76.2 87.63 0)
			(effects
				(font
					(size 1.27 1.27)
					(thickness 0.15)
				)
				(justify left bottom)
				(hide yes)
			)
		)
		(property "Datasheet" "https://spicat.kyocera-avx.com/product/mlcc/chartview/04025A330FAT2A/"
			(at 78.74 87.63 0)
			(effects
				(font
					(size 1.27 1.27)
					(thickness 0.15)
				)
				(justify left bottom)
				(hide yes)
			)
		)
		(property "Description" ""
			(at 63.5 107.95 0)
			(effects
				(font
					(size 1.27 1.27)
				)
				(hide yes)
			)
		)
		(property "MPN" "04025A330FAT2A"
			(at 81.28 87.63 0)
			(effects
				(font
					(size 1.27 1.27)
					(thickness 0.15)
				)
				(justify left bottom)
				(hide yes)
			)
		)
		(property "Manufacturer" "KYOCERA AVX"
			(at 83.82 87.63 0)
			(effects
				(font
					(size 1.27 1.27)
					(thickness 0.15)
				)
				(justify left bottom)
				(hide yes)
			)
		)
		(property "License" "Apache-2.0"
			(at 86.36 87.63 0)
			(effects
				(font
					(size 1.27 1.27)
					(thickness 0.15)
				)
				(justify left bottom)
				(hide yes)
			)
		)
		(property "Author" "Antmicro"
			(at 88.9 87.63 0)
			(effects
				(font
					(size 1.27 1.27)
					(thickness 0.15)
				)
				(justify left bottom)
				(hide yes)
			)
		)
		(property "Val" "33p"
			(at 66.04 106.68 90)
			(effects
				(font
					(size 1.27 1.27)
					(thickness 0.15)
				)
				(justify right)
			)
		)
		(property "Voltage" ""
			(at 91.44 87.63 0)
			(effects
				(font
					(size 1.27 1.27)
				)
				(justify left bottom)
				(hide yes)
			)
		)
		(property "Dielectric" ""
			(at 93.98 87.63 0)
			(effects
				(font
					(size 1.27 1.27)
				)
				(justify left bottom)
				(hide yes)
			)
		)
		(pin "1"
		)
		(pin "2"
		)
		(instances
			(project "gmsl-serializer"
				(path ""
					(reference "C17")
					(unit 1)
				)
			)
		)
	)
	(symbol
		(lib_id "antmicroResistors0402:R_0R_0402")
		(at 290.83 190.5 0)
		(mirror y)
		(unit 1)
		(exclude_from_sim no)
		(in_bom yes)
		(on_board yes)
		(dnp no)
		(property "Reference" "R33"
			(at 285.75 189.23 0)
			(effects
				(font
					(size 1.27 1.27)
					(thickness 0.15)
				)
				(justify left)
			)
		)
		(property "Value" "R_0R_0402"
			(at 270.51 203.2 0)
			(effects
				(font
					(size 1.27 1.27)
					(thickness 0.15)
				)
				(justify left bottom)
				(hide yes)
			)
		)
		(property "Footprint" "antmicro-footprints:R_0402_1005Metric"
			(at 270.51 205.74 0)
			(effects
				(font
					(size 1.27 1.27)
					(thickness 0.15)
				)
				(justify left bottom)
				(hide yes)
			)
		)
		(property "Datasheet" "https://industrial.panasonic.com/cdbs/www-data/pdf/RDA0000/AOA0000C301.pdf"
			(at 270.51 208.28 0)
			(effects
				(font
					(size 1.27 1.27)
					(thickness 0.15)
				)
				(justify left bottom)
				(hide yes)
			)
		)
		(property "Description" ""
			(at 290.83 190.5 0)
			(effects
				(font
					(size 1.27 1.27)
				)
				(hide yes)
			)
		)
		(property "MPN" "ERJ2GE0R00X"
			(at 270.51 210.82 0)
			(effects
				(font
					(size 1.27 1.27)
					(thickness 0.15)
				)
				(justify left bottom)
				(hide yes)
			)
		)
		(property "Manufacturer" "Panasonic"
			(at 270.51 213.36 0)
			(effects
				(font
					(size 1.27 1.27)
					(thickness 0.15)
				)
				(justify left bottom)
				(hide yes)
			)
		)
		(property "License" "Apache-2.0"
			(at 270.51 215.9 0)
			(effects
				(font
					(size 1.27 1.27)
					(thickness 0.15)
				)
				(justify left bottom)
				(hide yes)
			)
		)
		(property "Author" "Antmicro"
			(at 270.51 218.44 0)
			(effects
				(font
					(size 1.27 1.27)
					(thickness 0.15)
				)
				(justify left bottom)
				(hide yes)
			)
		)
		(property "Val" "0R"
			(at 292.1 189.23 0)
			(effects
				(font
					(size 1.27 1.27)
					(thickness 0.15)
				)
			)
		)
		(property "Tolerance" "~"
			(at 270.51 200.66 0)
			(effects
				(font
					(size 1.27 1.27)
				)
				(justify left bottom)
				(hide yes)
			)
		)
		(property "Current" "1A"
			(at 270.51 220.98 0)
			(effects
				(font
					(size 1.27 1.27)
					(thickness 0.15)
				)
				(justify left bottom)
				(hide yes)
			)
		)
		(pin "1"
		)
		(pin "2"
		)
		(instances
			(project "gmsl-serializer"
				(path ""
					(reference "R33")
					(unit 1)
				)
			)
		)
	)
	(symbol
		(lib_id "antmicroResistors0402:R_10k_0402")
		(at 234.95 171.45 270)
		(mirror x)
		(unit 1)
		(exclude_from_sim no)
		(in_bom yes)
		(on_board yes)
		(dnp no)
		(property "Reference" "R28"
			(at 233.045 167.64 90)
			(effects
				(font
					(size 1.27 1.27)
					(thickness 0.15)
				)
				(justify right)
			)
		)
		(property "Value" "R_10k_0402"
			(at 222.25 151.13 0)
			(effects
				(font
					(size 1.27 1.27)
					(thickness 0.15)
				)
				(justify left bottom)
				(hide yes)
			)
		)
		(property "Footprint" "antmicro-footprints:R_0402_1005Metric"
			(at 219.71 151.13 0)
			(effects
				(font
					(size 1.27 1.27)
					(thickness 0.15)
				)
				(justify left bottom)
				(hide yes)
			)
		)
		(property "Datasheet" "https://www.bourns.com/docs/product-datasheets/cr.pdf"
			(at 217.17 151.13 0)
			(effects
				(font
					(size 1.27 1.27)
					(thickness 0.15)
				)
				(justify left bottom)
				(hide yes)
			)
		)
		(property "Description" ""
			(at 234.95 171.45 0)
			(effects
				(font
					(size 1.27 1.27)
				)
				(hide yes)
			)
		)
		(property "MPN" "CR0402-FX-1002GLF"
			(at 214.63 151.13 0)
			(effects
				(font
					(size 1.27 1.27)
					(thickness 0.15)
				)
				(justify left bottom)
				(hide yes)
			)
		)
		(property "Manufacturer" "Bourns"
			(at 212.09 151.13 0)
			(effects
				(font
					(size 1.27 1.27)
					(thickness 0.15)
				)
				(justify left bottom)
				(hide yes)
			)
		)
		(property "License" "Apache-2.0"
			(at 209.55 151.13 0)
			(effects
				(font
					(size 1.27 1.27)
					(thickness 0.15)
				)
				(justify left bottom)
				(hide yes)
			)
		)
		(property "Author" "Antmicro"
			(at 207.01 151.13 0)
			(effects
				(font
					(size 1.27 1.27)
					(thickness 0.15)
				)
				(justify left bottom)
				(hide yes)
			)
		)
		(property "Val" "10k"
			(at 233.045 170.18 90)
			(effects
				(font
					(size 1.27 1.27)
					(thickness 0.15)
				)
				(justify right)
			)
		)
		(property "Tolerance" "1%"
			(at 224.79 151.13 0)
			(effects
				(font
					(size 1.27 1.27)
				)
				(justify left bottom)
				(hide yes)
			)
		)
		(pin "1"
		)
		(pin "2"
		)
		(instances
			(project "gmsl-serializer"
				(path ""
					(reference "R28")
					(unit 1)
				)
			)
		)
	)
	(symbol
		(lib_id "antmicroCapacitors0402:C_100n_0402")
		(at 233.68 184.15 90)
		(unit 1)
		(exclude_from_sim no)
		(in_bom yes)
		(on_board yes)
		(dnp no)
		(property "Reference" "C24"
			(at 234.315 179.705 90)
			(effects
				(font
					(size 1.27 1.27)
					(thickness 0.15)
				)
				(justify right)
			)
		)
		(property "Value" "C_100n_0402"
			(at 243.84 163.83 0)
			(effects
				(font
					(size 1.27 1.27)
					(thickness 0.15)
				)
				(justify left bottom)
				(hide yes)
			)
		)
		(property "Footprint" "antmicro-footprints:C_0402_1005Metric"
			(at 246.38 163.83 0)
			(effects
				(font
					(size 1.27 1.27)
					(thickness 0.15)
				)
				(justify left bottom)
				(hide yes)
			)
		)
		(property "Datasheet" "https://www.murata.com/products/productdetail?partno=GRM155R61H104KE14%23"
			(at 248.92 163.83 0)
			(effects
				(font
					(size 1.27 1.27)
					(thickness 0.15)
				)
				(justify left bottom)
				(hide yes)
			)
		)
		(property "Description" ""
			(at 233.68 184.15 0)
			(effects
				(font
					(size 1.27 1.27)
				)
				(hide yes)
			)
		)
		(property "MPN" "GRM155R61H104KE14D"
			(at 251.46 163.83 0)
			(effects
				(font
					(size 1.27 1.27)
					(thickness 0.15)
				)
				(justify left bottom)
				(hide yes)
			)
		)
		(property "Manufacturer" "Murata"
			(at 254 163.83 0)
			(effects
				(font
					(size 1.27 1.27)
					(thickness 0.15)
				)
				(justify left bottom)
				(hide yes)
			)
		)
		(property "License" "Apache-2.0"
			(at 256.54 163.83 0)
			(effects
				(font
					(size 1.27 1.27)
					(thickness 0.15)
				)
				(justify left bottom)
				(hide yes)
			)
		)
		(property "Author" "Antmicro"
			(at 259.08 163.83 0)
			(effects
				(font
					(size 1.27 1.27)
					(thickness 0.15)
				)
				(justify left bottom)
				(hide yes)
			)
		)
		(property "Val" "100n"
			(at 234.315 183.515 90)
			(effects
				(font
					(size 1.27 1.27)
					(thickness 0.15)
				)
				(justify right)
			)
		)
		(property "Voltage" "50V"
			(at 261.62 163.83 0)
			(effects
				(font
					(size 1.27 1.27)
				)
				(justify left bottom)
				(hide yes)
			)
		)
		(property "Dielectric" "X5R"
			(at 264.16 163.83 0)
			(effects
				(font
					(size 1.27 1.27)
				)
				(justify left bottom)
				(hide yes)
			)
		)
		(pin "1"
		)
		(pin "2"
		)
		(instances
			(project "gmsl-serializer"
				(path ""
					(reference "C24")
					(unit 1)
				)
			)
		)
	)
	(symbol
		(lib_id "antmicropower:GND")
		(at 220.98 185.42 0)
		(unit 1)
		(exclude_from_sim no)
		(in_bom yes)
		(on_board yes)
		(dnp no)
		(property "Reference" "#PWR0153"
			(at 229.87 187.96 0)
			(effects
				(font
					(size 1.27 1.27)
					(thickness 0.15)
				)
				(justify left bottom)
				(hide yes)
			)
		)
		(property "Value" "GND"
			(at 220.98 189.23 0)
			(effects
				(font
					(size 1.27 1.27)
					(thickness 0.15)
				)
			)
		)
		(property "Footprint" ""
			(at 229.87 193.04 0)
			(effects
				(font
					(size 1.27 1.27)
					(thickness 0.15)
				)
				(justify left bottom)
				(hide yes)
			)
		)
		(property "Datasheet" ""
			(at 229.87 198.12 0)
			(effects
				(font
					(size 1.27 1.27)
					(thickness 0.15)
				)
				(justify left bottom)
				(hide yes)
			)
		)
		(property "Description" ""
			(at 220.98 185.42 0)
			(effects
				(font
					(size 1.27 1.27)
				)
				(hide yes)
			)
		)
		(property "Author" "Antmicro"
			(at 229.87 193.04 0)
			(effects
				(font
					(size 1.27 1.27)
					(thickness 0.15)
				)
				(justify left bottom)
				(hide yes)
			)
		)
		(property "License" "Apache-2.0"
			(at 229.87 195.58 0)
			(effects
				(font
					(size 1.27 1.27)
					(thickness 0.15)
				)
				(justify left bottom)
				(hide yes)
			)
		)
		(pin "1"
		)
		(instances
			(project "gmsl-serializer"
				(path ""
					(reference "#PWR0153")
					(unit 1)
				)
			)
		)
	)
	(symbol
		(lib_id "antmicroCapacitors0402:C_10n_0402")
		(at 223.52 139.7 90)
		(unit 1)
		(exclude_from_sim no)
		(in_bom yes)
		(on_board yes)
		(dnp no)
		(property "Reference" "C32"
			(at 224.155 135.255 90)
			(effects
				(font
					(size 1.27 1.27)
					(thickness 0.15)
				)
				(justify right)
			)
		)
		(property "Value" "C_10n_0402"
			(at 233.68 119.38 0)
			(effects
				(font
					(size 1.27 1.27)
					(thickness 0.15)
				)
				(justify left bottom)
				(hide yes)
			)
		)
		(property "Footprint" "antmicro-footprints:C_0402_1005Metric"
			(at 236.22 119.38 0)
			(effects
				(font
					(size 1.27 1.27)
					(thickness 0.15)
				)
				(justify left bottom)
				(hide yes)
			)
		)
		(property "Datasheet" "https://www.murata.com/products/productdetail?partno=GRM155R71H103KA88%23"
			(at 238.76 119.38 0)
			(effects
				(font
					(size 1.27 1.27)
					(thickness 0.15)
				)
				(justify left bottom)
				(hide yes)
			)
		)
		(property "Description" ""
			(at 223.52 139.7 0)
			(effects
				(font
					(size 1.27 1.27)
				)
				(hide yes)
			)
		)
		(property "MPN" "GRM155R71H103KA88D"
			(at 241.3 119.38 0)
			(effects
				(font
					(size 1.27 1.27)
					(thickness 0.15)
				)
				(justify left bottom)
				(hide yes)
			)
		)
		(property "Manufacturer" "Murata"
			(at 243.84 119.38 0)
			(effects
				(font
					(size 1.27 1.27)
					(thickness 0.15)
				)
				(justify left bottom)
				(hide yes)
			)
		)
		(property "License" "Apache-2.0"
			(at 246.38 119.38 0)
			(effects
				(font
					(size 1.27 1.27)
					(thickness 0.15)
				)
				(justify left bottom)
				(hide yes)
			)
		)
		(property "Author" "Antmicro"
			(at 248.92 119.38 0)
			(effects
				(font
					(size 1.27 1.27)
					(thickness 0.15)
				)
				(justify left bottom)
				(hide yes)
			)
		)
		(property "Val" "10n"
			(at 224.155 139.065 90)
			(effects
				(font
					(size 1.27 1.27)
					(thickness 0.15)
				)
				(justify right)
			)
		)
		(property "Voltage" "50V"
			(at 251.46 119.38 0)
			(effects
				(font
					(size 1.27 1.27)
				)
				(justify left bottom)
				(hide yes)
			)
		)
		(property "Dielectric" "X7R"
			(at 254 119.38 0)
			(effects
				(font
					(size 1.27 1.27)
				)
				(justify left bottom)
				(hide yes)
			)
		)
		(pin "1"
		)
		(pin "2"
		)
		(instances
			(project "gmsl-serializer"
				(path ""
					(reference "C32")
					(unit 1)
				)
			)
		)
	)
	(symbol
		(lib_id "antmicroCapacitors0402:C_10u_0402")
		(at 215.9 139.7 90)
		(unit 1)
		(exclude_from_sim no)
		(in_bom yes)
		(on_board yes)
		(dnp no)
		(property "Reference" "C33"
			(at 216.535 135.255 90)
			(effects
				(font
					(size 1.27 1.27)
					(thickness 0.15)
				)
				(justify right)
			)
		)
		(property "Value" "C_10u_0402"
			(at 226.06 119.38 0)
			(effects
				(font
					(size 1.27 1.27)
					(thickness 0.15)
				)
				(justify left bottom)
				(hide yes)
			)
		)
		(property "Footprint" "antmicro-footprints:C_0402_1005Metric"
			(at 228.6 119.38 0)
			(effects
				(font
					(size 1.27 1.27)
					(thickness 0.15)
				)
				(justify left bottom)
				(hide yes)
			)
		)
		(property "Datasheet" "https://www.yageo.com/en/Chart/Download/pdf/CC0402MRX5R5BB106"
			(at 231.14 119.38 0)
			(effects
				(font
					(size 1.27 1.27)
					(thickness 0.15)
				)
				(justify left bottom)
				(hide yes)
			)
		)
		(property "Description" ""
			(at 215.9 139.7 0)
			(effects
				(font
					(size 1.27 1.27)
				)
				(hide yes)
			)
		)
		(property "MPN" "CC0402MRX5R5BB106"
			(at 233.68 119.38 0)
			(effects
				(font
					(size 1.27 1.27)
					(thickness 0.15)
				)
				(justify left bottom)
				(hide yes)
			)
		)
		(property "Manufacturer" "YAGEO"
			(at 236.22 119.38 0)
			(effects
				(font
					(size 1.27 1.27)
					(thickness 0.15)
				)
				(justify left bottom)
				(hide yes)
			)
		)
		(property "License" "Apache-2.0"
			(at 238.76 119.38 0)
			(effects
				(font
					(size 1.27 1.27)
					(thickness 0.15)
				)
				(justify left bottom)
				(hide yes)
			)
		)
		(property "Author" "Antmicro"
			(at 241.3 119.38 0)
			(effects
				(font
					(size 1.27 1.27)
					(thickness 0.15)
				)
				(justify left bottom)
				(hide yes)
			)
		)
		(property "Val" "10u"
			(at 216.535 139.065 90)
			(effects
				(font
					(size 1.27 1.27)
					(thickness 0.15)
				)
				(justify right)
			)
		)
		(property "Voltage" ""
			(at 243.84 119.38 0)
			(effects
				(font
					(size 1.27 1.27)
				)
				(justify left bottom)
				(hide yes)
			)
		)
		(property "Dielectric" ""
			(at 246.38 119.38 0)
			(effects
				(font
					(size 1.27 1.27)
				)
				(justify left bottom)
				(hide yes)
			)
		)
		(pin "1"
		)
		(pin "2"
		)
		(instances
			(project "gmsl-serializer"
				(path ""
					(reference "C33")
					(unit 1)
				)
			)
		)
	)
	(symbol
		(lib_id "antmicroCapacitors0402:C_10n_0402")
		(at 240.03 184.15 90)
		(unit 1)
		(exclude_from_sim no)
		(in_bom yes)
		(on_board yes)
		(dnp no)
		(property "Reference" "C23"
			(at 240.665 179.705 90)
			(effects
				(font
					(size 1.27 1.27)
					(thickness 0.15)
				)
				(justify right)
			)
		)
		(property "Value" "C_10n_0402"
			(at 250.19 163.83 0)
			(effects
				(font
					(size 1.27 1.27)
					(thickness 0.15)
				)
				(justify left bottom)
				(hide yes)
			)
		)
		(property "Footprint" "antmicro-footprints:C_0402_1005Metric"
			(at 252.73 163.83 0)
			(effects
				(font
					(size 1.27 1.27)
					(thickness 0.15)
				)
				(justify left bottom)
				(hide yes)
			)
		)
		(property "Datasheet" "https://www.murata.com/products/productdetail?partno=GRM155R71H103KA88%23"
			(at 255.27 163.83 0)
			(effects
				(font
					(size 1.27 1.27)
					(thickness 0.15)
				)
				(justify left bottom)
				(hide yes)
			)
		)
		(property "Description" ""
			(at 240.03 184.15 0)
			(effects
				(font
					(size 1.27 1.27)
				)
				(hide yes)
			)
		)
		(property "MPN" "GRM155R71H103KA88D"
			(at 257.81 163.83 0)
			(effects
				(font
					(size 1.27 1.27)
					(thickness 0.15)
				)
				(justify left bottom)
				(hide yes)
			)
		)
		(property "Manufacturer" "Murata"
			(at 260.35 163.83 0)
			(effects
				(font
					(size 1.27 1.27)
					(thickness 0.15)
				)
				(justify left bottom)
				(hide yes)
			)
		)
		(property "License" "Apache-2.0"
			(at 262.89 163.83 0)
			(effects
				(font
					(size 1.27 1.27)
					(thickness 0.15)
				)
				(justify left bottom)
				(hide yes)
			)
		)
		(property "Author" "Antmicro"
			(at 265.43 163.83 0)
			(effects
				(font
					(size 1.27 1.27)
					(thickness 0.15)
				)
				(justify left bottom)
				(hide yes)
			)
		)
		(property "Val" "10n"
			(at 240.665 183.515 90)
			(effects
				(font
					(size 1.27 1.27)
					(thickness 0.15)
				)
				(justify right)
			)
		)
		(property "Voltage" "50V"
			(at 267.97 163.83 0)
			(effects
				(font
					(size 1.27 1.27)
				)
				(justify left bottom)
				(hide yes)
			)
		)
		(property "Dielectric" "X7R"
			(at 270.51 163.83 0)
			(effects
				(font
					(size 1.27 1.27)
				)
				(justify left bottom)
				(hide yes)
			)
		)
		(pin "1"
		)
		(pin "2"
		)
		(instances
			(project "gmsl-serializer"
				(path ""
					(reference "C23")
					(unit 1)
				)
			)
		)
	)
	(symbol
		(lib_id "antmicroTestPoints:TP_1.5mm_SMD")
		(at 275.59 165.1 0)
		(unit 1)
		(exclude_from_sim no)
		(in_bom no)
		(on_board yes)
		(dnp no)
		(property "Reference" "TP6"
			(at 276.225 163.83 0)
			(effects
				(font
					(size 1.27 1.27)
					(thickness 0.15)
				)
				(justify right)
			)
		)
		(property "Value" "TP_1.5mm_SMD"
			(at 290.83 172.72 0)
			(effects
				(font
					(size 1.27 1.27)
					(thickness 0.15)
				)
				(justify left bottom)
				(hide yes)
			)
		)
		(property "Footprint" "antmicro-footprints:TP_SMD_1.5mm"
			(at 290.83 175.26 0)
			(effects
				(font
					(size 1.27 1.27)
					(thickness 0.15)
				)
				(justify left bottom)
				(hide yes)
			)
		)
		(property "Datasheet" ""
			(at 293.37 177.8 0)
			(effects
				(font
					(size 1.27 1.27)
					(thickness 0.15)
				)
				(justify left bottom)
				(hide yes)
			)
		)
		(property "Description" ""
			(at 275.59 165.1 0)
			(effects
				(font
					(size 1.27 1.27)
				)
				(hide yes)
			)
		)
		(property "MPN" ""
			(at 275.59 165.1 0)
			(effects
				(font
					(size 1.27 1.27)
				)
				(hide yes)
			)
		)
		(property "Manufacturer" ""
			(at 275.59 165.1 0)
			(effects
				(font
					(size 1.27 1.27)
				)
				(hide yes)
			)
		)
		(property "Author" "Antmicro"
			(at 290.83 180.34 0)
			(effects
				(font
					(size 1.27 1.27)
					(thickness 0.15)
				)
				(justify left bottom)
				(hide yes)
			)
		)
		(property "License" "Apache-2.0"
			(at 290.83 182.88 0)
			(effects
				(font
					(size 1.27 1.27)
					(thickness 0.15)
				)
				(justify left bottom)
				(hide yes)
			)
		)
		(pin "1"
		)
		(instances
			(project "gmsl-serializer"
				(path ""
					(reference "TP6")
					(unit 1)
				)
			)
		)
	)
	(symbol
		(lib_id "antmicroResistors0402:R_51R_0402")
		(at 222.25 165.1 270)
		(mirror x)
		(unit 1)
		(exclude_from_sim no)
		(in_bom yes)
		(on_board yes)
		(dnp no)
		(fields_autoplaced yes)
		(property "Reference" "R29"
			(at 219.71 161.2899 90)
			(effects
				(font
					(size 1.27 1.27)
					(thickness 0.15)
				)
				(justify right)
			)
		)
		(property "Value" "R_51R_0402"
			(at 209.55 144.78 0)
			(effects
				(font
					(size 1.27 1.27)
					(thickness 0.15)
				)
				(justify left bottom)
				(hide yes)
			)
		)
		(property "Footprint" "antmicro-footprints:R_0402_1005Metric"
			(at 207.01 144.78 0)
			(effects
				(font
					(size 1.27 1.27)
					(thickness 0.15)
				)
				(justify left bottom)
				(hide yes)
			)
		)
		(property "Datasheet" "https://www.bourns.com/docs/product-datasheets/cr.pdf"
			(at 204.47 144.78 0)
			(effects
				(font
					(size 1.27 1.27)
					(thickness 0.15)
				)
				(justify left bottom)
				(hide yes)
			)
		)
		(property "Description" ""
			(at 222.25 165.1 0)
			(effects
				(font
					(size 1.27 1.27)
				)
				(hide yes)
			)
		)
		(property "MPN" "CR0402-FX-51R0GLF"
			(at 201.93 144.78 0)
			(effects
				(font
					(size 1.27 1.27)
					(thickness 0.15)
				)
				(justify left bottom)
				(hide yes)
			)
		)
		(property "Manufacturer" "Bourns"
			(at 199.39 144.78 0)
			(effects
				(font
					(size 1.27 1.27)
					(thickness 0.15)
				)
				(justify left bottom)
				(hide yes)
			)
		)
		(property "License" "Apache-2.0"
			(at 196.85 144.78 0)
			(effects
				(font
					(size 1.27 1.27)
					(thickness 0.15)
				)
				(justify left bottom)
				(hide yes)
			)
		)
		(property "Author" "Antmicro"
			(at 194.31 144.78 0)
			(effects
				(font
					(size 1.27 1.27)
					(thickness 0.15)
				)
				(justify left bottom)
				(hide yes)
			)
		)
		(property "Val" "51R"
			(at 219.71 163.8299 90)
			(effects
				(font
					(size 1.27 1.27)
					(thickness 0.15)
				)
				(justify right)
			)
		)
		(property "Tolerance" "1%"
			(at 212.09 144.78 0)
			(effects
				(font
					(size 1.27 1.27)
				)
				(justify left bottom)
				(hide yes)
			)
		)
		(pin "1"
		)
		(pin "2"
		)
		(instances
			(project "gmsl-serializer"
				(path ""
					(reference "R29")
					(unit 1)
				)
			)
		)
	)
	(symbol
		(lib_id "antmicropower:+1V2")
		(at 215.9 90.17 0)
		(unit 1)
		(exclude_from_sim no)
		(in_bom yes)
		(on_board yes)
		(dnp no)
		(property "Reference" "#PWR0144"
			(at 215.9 93.98 0)
			(effects
				(font
					(size 1.27 1.27)
				)
				(hide yes)
			)
		)
		(property "Value" "+1V2"
			(at 215.9 86.36 0)
			(effects
				(font
					(size 1.27 1.27)
				)
			)
		)
		(property "Footprint" ""
			(at 215.9 90.17 0)
			(effects
				(font
					(size 1.27 1.27)
				)
				(hide yes)
			)
		)
		(property "Datasheet" ""
			(at 215.9 90.17 0)
			(effects
				(font
					(size 1.27 1.27)
				)
				(hide yes)
			)
		)
		(property "Description" ""
			(at 215.9 90.17 0)
			(effects
				(font
					(size 1.27 1.27)
				)
				(hide yes)
			)
		)
		(pin "1"
		)
		(instances
			(project "gmsl-serializer"
				(path ""
					(reference "#PWR0144")
					(unit 1)
				)
			)
		)
	)
	(symbol
		(lib_id "antmicroResistors0402:R_402R_0402")
		(at 220.98 184.15 270)
		(mirror x)
		(unit 1)
		(exclude_from_sim no)
		(in_bom yes)
		(on_board yes)
		(dnp no)
		(property "Reference" "R23"
			(at 219.71 180.34 90)
			(effects
				(font
					(size 1.27 1.27)
					(thickness 0.15)
				)
				(justify right)
			)
		)
		(property "Value" "R_402R_0402"
			(at 208.28 163.83 0)
			(effects
				(font
					(size 1.27 1.27)
					(thickness 0.15)
				)
				(justify left bottom)
				(hide yes)
			)
		)
		(property "Footprint" "antmicro-footprints:R_0402_1005Metric"
			(at 205.74 163.83 0)
			(effects
				(font
					(size 1.27 1.27)
					(thickness 0.15)
				)
				(justify left bottom)
				(hide yes)
			)
		)
		(property "Datasheet" "https://www.mouser.com/datasheet/2/54/cr-1858361.pdf"
			(at 203.2 163.83 0)
			(effects
				(font
					(size 1.27 1.27)
					(thickness 0.15)
				)
				(justify left bottom)
				(hide yes)
			)
		)
		(property "Description" ""
			(at 220.98 184.15 0)
			(effects
				(font
					(size 1.27 1.27)
				)
				(hide yes)
			)
		)
		(property "MPN" "CR0402-FX-4020GLF"
			(at 200.66 163.83 0)
			(effects
				(font
					(size 1.27 1.27)
					(thickness 0.15)
				)
				(justify left bottom)
				(hide yes)
			)
		)
		(property "Manufacturer" "Bourns"
			(at 198.12 163.83 0)
			(effects
				(font
					(size 1.27 1.27)
					(thickness 0.15)
				)
				(justify left bottom)
				(hide yes)
			)
		)
		(property "License" "Apache-2.0"
			(at 195.58 163.83 0)
			(effects
				(font
					(size 1.27 1.27)
					(thickness 0.15)
				)
				(justify left bottom)
				(hide yes)
			)
		)
		(property "Author" "Antmicro"
			(at 193.04 163.83 0)
			(effects
				(font
					(size 1.27 1.27)
					(thickness 0.15)
				)
				(justify left bottom)
				(hide yes)
			)
		)
		(property "Val" "402R"
			(at 219.71 182.88 90)
			(effects
				(font
					(size 1.27 1.27)
					(thickness 0.15)
				)
				(justify right)
			)
		)
		(property "Tolerance" "1%"
			(at 210.82 163.83 0)
			(effects
				(font
					(size 1.27 1.27)
				)
				(justify left bottom)
				(hide yes)
			)
		)
		(pin "1"
		)
		(pin "2"
		)
		(instances
			(project "gmsl-serializer"
				(path ""
					(reference "R23")
					(unit 1)
				)
			)
		)
	)
	(symbol
		(lib_id "antmicroCapacitors0402:C_100n_0402")
		(at 231.14 158.75 180)
		(unit 1)
		(exclude_from_sim no)
		(in_bom yes)
		(on_board yes)
		(dnp no)
		(property "Reference" "C31"
			(at 231.14 157.48 0)
			(effects
				(font
					(size 1.27 1.27)
					(thickness 0.15)
				)
			)
		)
		(property "Value" "C_100n_0402"
			(at 210.82 148.59 0)
			(effects
				(font
					(size 1.27 1.27)
					(thickness 0.15)
				)
				(justify left bottom)
				(hide yes)
			)
		)
		(property "Footprint" "antmicro-footprints:C_0402_1005Metric"
			(at 210.82 146.05 0)
			(effects
				(font
					(size 1.27 1.27)
					(thickness 0.15)
				)
				(justify left bottom)
				(hide yes)
			)
		)
		(property "Datasheet" "https://www.murata.com/products/productdetail?partno=GRM155R61H104KE14%23"
			(at 210.82 143.51 0)
			(effects
				(font
					(size 1.27 1.27)
					(thickness 0.15)
				)
				(justify left bottom)
				(hide yes)
			)
		)
		(property "Description" ""
			(at 231.14 158.75 0)
			(effects
				(font
					(size 1.27 1.27)
				)
				(hide yes)
			)
		)
		(property "MPN" "GRM155R61H104KE14D"
			(at 210.82 140.97 0)
			(effects
				(font
					(size 1.27 1.27)
					(thickness 0.15)
				)
				(justify left bottom)
				(hide yes)
			)
		)
		(property "Manufacturer" "Murata"
			(at 210.82 138.43 0)
			(effects
				(font
					(size 1.27 1.27)
					(thickness 0.15)
				)
				(justify left bottom)
				(hide yes)
			)
		)
		(property "License" "Apache-2.0"
			(at 210.82 135.89 0)
			(effects
				(font
					(size 1.27 1.27)
					(thickness 0.15)
				)
				(justify left bottom)
				(hide yes)
			)
		)
		(property "Author" "Antmicro"
			(at 210.82 133.35 0)
			(effects
				(font
					(size 1.27 1.27)
					(thickness 0.15)
				)
				(justify left bottom)
				(hide yes)
			)
		)
		(property "Val" "100n"
			(at 224.79 157.48 0)
			(effects
				(font
					(size 1.27 1.27)
					(thickness 0.15)
				)
			)
		)
		(property "Voltage" "50V"
			(at 210.82 130.81 0)
			(effects
				(font
					(size 1.27 1.27)
				)
				(justify left bottom)
				(hide yes)
			)
		)
		(property "Dielectric" "X5R"
			(at 210.82 128.27 0)
			(effects
				(font
					(size 1.27 1.27)
				)
				(justify left bottom)
				(hide yes)
			)
		)
		(pin "1"
		)
		(pin "2"
		)
		(instances
			(project "gmsl-serializer"
				(path ""
					(reference "C31")
					(unit 1)
				)
			)
		)
	)
	(symbol
		(lib_id "antmicroCapacitors0402:C_10u_0402")
		(at 215.9 97.79 270)
		(mirror x)
		(unit 1)
		(exclude_from_sim no)
		(in_bom yes)
		(on_board yes)
		(dnp no)
		(property "Reference" "C18"
			(at 220.345 93.345 90)
			(effects
				(font
					(size 1.27 1.27)
					(thickness 0.15)
				)
				(justify right)
			)
		)
		(property "Value" "C_10u_0402"
			(at 205.74 77.47 0)
			(effects
				(font
					(size 1.27 1.27)
					(thickness 0.15)
				)
				(justify left bottom)
				(hide yes)
			)
		)
		(property "Footprint" "antmicro-footprints:C_0402_1005Metric"
			(at 203.2 77.47 0)
			(effects
				(font
					(size 1.27 1.27)
					(thickness 0.15)
				)
				(justify left bottom)
				(hide yes)
			)
		)
		(property "Datasheet" "https://www.yageo.com/en/Chart/Download/pdf/CC0402MRX5R5BB106"
			(at 200.66 77.47 0)
			(effects
				(font
					(size 1.27 1.27)
					(thickness 0.15)
				)
				(justify left bottom)
				(hide yes)
			)
		)
		(property "Description" ""
			(at 215.9 97.79 0)
			(effects
				(font
					(size 1.27 1.27)
				)
				(hide yes)
			)
		)
		(property "MPN" "CC0402MRX5R5BB106"
			(at 198.12 77.47 0)
			(effects
				(font
					(size 1.27 1.27)
					(thickness 0.15)
				)
				(justify left bottom)
				(hide yes)
			)
		)
		(property "Manufacturer" "YAGEO"
			(at 195.58 77.47 0)
			(effects
				(font
					(size 1.27 1.27)
					(thickness 0.15)
				)
				(justify left bottom)
				(hide yes)
			)
		)
		(property "License" "Apache-2.0"
			(at 193.04 77.47 0)
			(effects
				(font
					(size 1.27 1.27)
					(thickness 0.15)
				)
				(justify left bottom)
				(hide yes)
			)
		)
		(property "Author" "Antmicro"
			(at 190.5 77.47 0)
			(effects
				(font
					(size 1.27 1.27)
					(thickness 0.15)
				)
				(justify left bottom)
				(hide yes)
			)
		)
		(property "Val" "10u"
			(at 220.345 97.79 90)
			(effects
				(font
					(size 1.27 1.27)
					(thickness 0.15)
				)
				(justify right)
			)
		)
		(property "Voltage" ""
			(at 187.96 77.47 0)
			(effects
				(font
					(size 1.27 1.27)
				)
				(justify left bottom)
				(hide yes)
			)
		)
		(property "Dielectric" ""
			(at 185.42 77.47 0)
			(effects
				(font
					(size 1.27 1.27)
				)
				(justify left bottom)
				(hide yes)
			)
		)
		(pin "1"
		)
		(pin "2"
		)
		(instances
			(project "gmsl-serializer"
				(path ""
					(reference "C18")
					(unit 1)
				)
			)
		)
	)
	(symbol
		(lib_id "antmicropower:+3V3")
		(at 82.55 195.58 0)
		(unit 1)
		(exclude_from_sim no)
		(in_bom yes)
		(on_board yes)
		(dnp no)
		(property "Reference" "#PWR0158"
			(at 97.79 198.12 0)
			(effects
				(font
					(size 1.27 1.27)
					(thickness 0.15)
				)
				(justify left bottom)
				(hide yes)
			)
		)
		(property "Value" "+3V3"
			(at 82.55 191.77 0)
			(effects
				(font
					(size 1.27 1.27)
					(thickness 0.15)
				)
			)
		)
		(property "Footprint" ""
			(at 97.79 203.2 0)
			(effects
				(font
					(size 1.27 1.27)
					(thickness 0.15)
				)
				(justify left bottom)
				(hide yes)
			)
		)
		(property "Datasheet" ""
			(at 97.79 205.74 0)
			(effects
				(font
					(size 1.27 1.27)
					(thickness 0.15)
				)
				(justify left bottom)
				(hide yes)
			)
		)
		(property "Description" ""
			(at 82.55 195.58 0)
			(effects
				(font
					(size 1.27 1.27)
				)
				(hide yes)
			)
		)
		(property "Author" "Antmicro"
			(at 97.79 203.2 0)
			(effects
				(font
					(size 1.27 1.27)
					(thickness 0.15)
				)
				(justify left bottom)
				(hide yes)
			)
		)
		(property "License" "Apache-2.0"
			(at 97.79 205.74 0)
			(effects
				(font
					(size 1.27 1.27)
					(thickness 0.15)
				)
				(justify left bottom)
				(hide yes)
			)
		)
		(pin "1"
		)
		(instances
			(project "gmsl-serializer"
				(path ""
					(reference "#PWR0158")
					(unit 1)
				)
			)
		)
	)
	(symbol
		(lib_id "antmicroResistors0402:R_0R_0402")
		(at 290.83 185.42 0)
		(mirror y)
		(unit 1)
		(exclude_from_sim no)
		(in_bom no)
		(on_board yes)
		(dnp yes)
		(property "Reference" "R31"
			(at 285.75 184.15 0)
			(effects
				(font
					(size 1.27 1.27)
					(thickness 0.15)
				)
				(justify left)
			)
		)
		(property "Value" "R_0R_0402"
			(at 270.51 198.12 0)
			(effects
				(font
					(size 1.27 1.27)
					(thickness 0.15)
				)
				(justify left bottom)
				(hide yes)
			)
		)
		(property "Footprint" "antmicro-footprints:R_0402_1005Metric"
			(at 270.51 200.66 0)
			(effects
				(font
					(size 1.27 1.27)
					(thickness 0.15)
				)
				(justify left bottom)
				(hide yes)
			)
		)
		(property "Datasheet" "https://industrial.panasonic.com/cdbs/www-data/pdf/RDA0000/AOA0000C301.pdf"
			(at 270.51 203.2 0)
			(effects
				(font
					(size 1.27 1.27)
					(thickness 0.15)
				)
				(justify left bottom)
				(hide yes)
			)
		)
		(property "Description" ""
			(at 290.83 185.42 0)
			(effects
				(font
					(size 1.27 1.27)
				)
				(hide yes)
			)
		)
		(property "MPN" "ERJ2GE0R00X"
			(at 270.51 205.74 0)
			(effects
				(font
					(size 1.27 1.27)
					(thickness 0.15)
				)
				(justify left bottom)
				(hide yes)
			)
		)
		(property "Manufacturer" "Panasonic"
			(at 270.51 208.28 0)
			(effects
				(font
					(size 1.27 1.27)
					(thickness 0.15)
				)
				(justify left bottom)
				(hide yes)
			)
		)
		(property "License" "Apache-2.0"
			(at 270.51 210.82 0)
			(effects
				(font
					(size 1.27 1.27)
					(thickness 0.15)
				)
				(justify left bottom)
				(hide yes)
			)
		)
		(property "Author" "Antmicro"
			(at 270.51 213.36 0)
			(effects
				(font
					(size 1.27 1.27)
					(thickness 0.15)
				)
				(justify left bottom)
				(hide yes)
			)
		)
		(property "Val" "0R"
			(at 292.1 184.15 0)
			(effects
				(font
					(size 1.27 1.27)
					(thickness 0.15)
				)
			)
		)
		(property "Tolerance" "~"
			(at 270.51 195.58 0)
			(effects
				(font
					(size 1.27 1.27)
				)
				(justify left bottom)
				(hide yes)
			)
		)
		(property "Current" "1A"
			(at 270.51 215.9 0)
			(effects
				(font
					(size 1.27 1.27)
					(thickness 0.15)
				)
				(justify left bottom)
				(hide yes)
			)
		)
		(pin "1"
		)
		(pin "2"
		)
		(instances
			(project "gmsl-serializer"
				(path ""
					(reference "R31")
					(unit 1)
				)
			)
		)
	)
	(symbol
		(lib_id "antmicropower:GND")
		(at 215.9 142.24 0)
		(unit 1)
		(exclude_from_sim no)
		(in_bom yes)
		(on_board yes)
		(dnp no)
		(property "Reference" "#PWR0138"
			(at 224.79 144.78 0)
			(effects
				(font
					(size 1.27 1.27)
					(thickness 0.15)
				)
				(justify left bottom)
				(hide yes)
			)
		)
		(property "Value" "GND"
			(at 215.9 146.05 0)
			(effects
				(font
					(size 1.27 1.27)
					(thickness 0.15)
				)
			)
		)
		(property "Footprint" ""
			(at 224.79 149.86 0)
			(effects
				(font
					(size 1.27 1.27)
					(thickness 0.15)
				)
				(justify left bottom)
				(hide yes)
			)
		)
		(property "Datasheet" ""
			(at 224.79 154.94 0)
			(effects
				(font
					(size 1.27 1.27)
					(thickness 0.15)
				)
				(justify left bottom)
				(hide yes)
			)
		)
		(property "Description" ""
			(at 215.9 142.24 0)
			(effects
				(font
					(size 1.27 1.27)
				)
				(hide yes)
			)
		)
		(property "Author" "Antmicro"
			(at 224.79 149.86 0)
			(effects
				(font
					(size 1.27 1.27)
					(thickness 0.15)
				)
				(justify left bottom)
				(hide yes)
			)
		)
		(property "License" "Apache-2.0"
			(at 224.79 152.4 0)
			(effects
				(font
					(size 1.27 1.27)
					(thickness 0.15)
				)
				(justify left bottom)
				(hide yes)
			)
		)
		(pin "1"
		)
		(instances
			(project "gmsl-serializer"
				(path ""
					(reference "#PWR0138")
					(unit 1)
				)
			)
		)
	)
	(symbol
		(lib_id "antmicropower:GND")
		(at 82.55 213.36 0)
		(unit 1)
		(exclude_from_sim no)
		(in_bom yes)
		(on_board yes)
		(dnp no)
		(property "Reference" "#PWR0147"
			(at 91.44 215.9 0)
			(effects
				(font
					(size 1.27 1.27)
					(thickness 0.15)
				)
				(justify left bottom)
				(hide yes)
			)
		)
		(property "Value" "GND"
			(at 82.55 217.17 0)
			(effects
				(font
					(size 1.27 1.27)
					(thickness 0.15)
				)
			)
		)
		(property "Footprint" ""
			(at 91.44 220.98 0)
			(effects
				(font
					(size 1.27 1.27)
					(thickness 0.15)
				)
				(justify left bottom)
				(hide yes)
			)
		)
		(property "Datasheet" ""
			(at 91.44 226.06 0)
			(effects
				(font
					(size 1.27 1.27)
					(thickness 0.15)
				)
				(justify left bottom)
				(hide yes)
			)
		)
		(property "Description" ""
			(at 82.55 213.36 0)
			(effects
				(font
					(size 1.27 1.27)
				)
				(hide yes)
			)
		)
		(property "Author" "Antmicro"
			(at 91.44 220.98 0)
			(effects
				(font
					(size 1.27 1.27)
					(thickness 0.15)
				)
				(justify left bottom)
				(hide yes)
			)
		)
		(property "License" "Apache-2.0"
			(at 91.44 223.52 0)
			(effects
				(font
					(size 1.27 1.27)
					(thickness 0.15)
				)
				(justify left bottom)
				(hide yes)
			)
		)
		(pin "1"
		)
		(instances
			(project "gmsl-serializer"
				(path ""
					(reference "#PWR0147")
					(unit 1)
				)
			)
		)
	)
	(symbol
		(lib_id "antmicroResistors0402:R_10k_0402")
		(at 82.55 201.93 90)
		(unit 1)
		(exclude_from_sim no)
		(in_bom yes)
		(on_board yes)
		(dnp no)
		(fields_autoplaced yes)
		(property "Reference" "R21"
			(at 85.09 198.12 90)
			(effects
				(font
					(size 1.27 1.27)
					(thickness 0.15)
				)
				(justify right)
			)
		)
		(property "Value" "R_10k_0402"
			(at 95.25 181.61 0)
			(effects
				(font
					(size 1.27 1.27)
					(thickness 0.15)
				)
				(justify left bottom)
				(hide yes)
			)
		)
		(property "Footprint" "antmicro-footprints:R_0402_1005Metric"
			(at 97.79 181.61 0)
			(effects
				(font
					(size 1.27 1.27)
					(thickness 0.15)
				)
				(justify left bottom)
				(hide yes)
			)
		)
		(property "Datasheet" "https://www.bourns.com/docs/product-datasheets/cr.pdf"
			(at 100.33 181.61 0)
			(effects
				(font
					(size 1.27 1.27)
					(thickness 0.15)
				)
				(justify left bottom)
				(hide yes)
			)
		)
		(property "Description" ""
			(at 82.55 201.93 0)
			(effects
				(font
					(size 1.27 1.27)
				)
				(hide yes)
			)
		)
		(property "MPN" "CR0402-FX-1002GLF"
			(at 102.87 181.61 0)
			(effects
				(font
					(size 1.27 1.27)
					(thickness 0.15)
				)
				(justify left bottom)
				(hide yes)
			)
		)
		(property "Manufacturer" "Bourns"
			(at 105.41 181.61 0)
			(effects
				(font
					(size 1.27 1.27)
					(thickness 0.15)
				)
				(justify left bottom)
				(hide yes)
			)
		)
		(property "License" "Apache-2.0"
			(at 107.95 181.61 0)
			(effects
				(font
					(size 1.27 1.27)
					(thickness 0.15)
				)
				(justify left bottom)
				(hide yes)
			)
		)
		(property "Author" "Antmicro"
			(at 110.49 181.61 0)
			(effects
				(font
					(size 1.27 1.27)
					(thickness 0.15)
				)
				(justify left bottom)
				(hide yes)
			)
		)
		(property "Val" "10k"
			(at 85.09 200.66 90)
			(effects
				(font
					(size 1.27 1.27)
					(thickness 0.15)
				)
				(justify right)
			)
		)
		(property "Tolerance" "1%"
			(at 92.71 181.61 0)
			(effects
				(font
					(size 1.27 1.27)
				)
				(justify left bottom)
				(hide yes)
			)
		)
		(pin "1"
		)
		(pin "2"
		)
		(instances
			(project "gmsl-serializer"
				(path ""
					(reference "R21")
					(unit 1)
				)
			)
		)
	)
	(symbol
		(lib_id "antmicroCapacitors0402:C_100n_0402")
		(at 231.14 97.79 90)
		(unit 1)
		(exclude_from_sim no)
		(in_bom yes)
		(on_board yes)
		(dnp no)
		(property "Reference" "C22"
			(at 231.775 93.345 90)
			(effects
				(font
					(size 1.27 1.27)
					(thickness 0.15)
				)
				(justify right)
			)
		)
		(property "Value" "C_100n_0402"
			(at 241.3 77.47 0)
			(effects
				(font
					(size 1.27 1.27)
					(thickness 0.15)
				)
				(justify left bottom)
				(hide yes)
			)
		)
		(property "Footprint" "antmicro-footprints:C_0402_1005Metric"
			(at 243.84 77.47 0)
			(effects
				(font
					(size 1.27 1.27)
					(thickness 0.15)
				)
				(justify left bottom)
				(hide yes)
			)
		)
		(property "Datasheet" "https://www.murata.com/products/productdetail?partno=GRM155R61H104KE14%23"
			(at 246.38 77.47 0)
			(effects
				(font
					(size 1.27 1.27)
					(thickness 0.15)
				)
				(justify left bottom)
				(hide yes)
			)
		)
		(property "Description" ""
			(at 231.14 97.79 0)
			(effects
				(font
					(size 1.27 1.27)
				)
				(hide yes)
			)
		)
		(property "MPN" "GRM155R61H104KE14D"
			(at 248.92 77.47 0)
			(effects
				(font
					(size 1.27 1.27)
					(thickness 0.15)
				)
				(justify left bottom)
				(hide yes)
			)
		)
		(property "Manufacturer" "Murata"
			(at 251.46 77.47 0)
			(effects
				(font
					(size 1.27 1.27)
					(thickness 0.15)
				)
				(justify left bottom)
				(hide yes)
			)
		)
		(property "License" "Apache-2.0"
			(at 254 77.47 0)
			(effects
				(font
					(size 1.27 1.27)
					(thickness 0.15)
				)
				(justify left bottom)
				(hide yes)
			)
		)
		(property "Author" "Antmicro"
			(at 256.54 77.47 0)
			(effects
				(font
					(size 1.27 1.27)
					(thickness 0.15)
				)
				(justify left bottom)
				(hide yes)
			)
		)
		(property "Val" "100n"
			(at 231.775 97.79 90)
			(effects
				(font
					(size 1.27 1.27)
					(thickness 0.15)
				)
				(justify right)
			)
		)
		(property "Voltage" "50V"
			(at 259.08 77.47 0)
			(effects
				(font
					(size 1.27 1.27)
				)
				(justify left bottom)
				(hide yes)
			)
		)
		(property "Dielectric" "X5R"
			(at 261.62 77.47 0)
			(effects
				(font
					(size 1.27 1.27)
				)
				(justify left bottom)
				(hide yes)
			)
		)
		(pin "1"
		)
		(pin "2"
		)
		(instances
			(project "gmsl-serializer"
				(path ""
					(reference "C22")
					(unit 1)
				)
			)
		)
	)
	(symbol
		(lib_id "antmicroCapacitors0402:C_100n_0402")
		(at 223.52 97.79 90)
		(unit 1)
		(exclude_from_sim no)
		(in_bom yes)
		(on_board yes)
		(dnp no)
		(property "Reference" "C20"
			(at 224.155 93.345 90)
			(effects
				(font
					(size 1.27 1.27)
					(thickness 0.15)
				)
				(justify right)
			)
		)
		(property "Value" "C_100n_0402"
			(at 233.68 77.47 0)
			(effects
				(font
					(size 1.27 1.27)
					(thickness 0.15)
				)
				(justify left bottom)
				(hide yes)
			)
		)
		(property "Footprint" "antmicro-footprints:C_0402_1005Metric"
			(at 236.22 77.47 0)
			(effects
				(font
					(size 1.27 1.27)
					(thickness 0.15)
				)
				(justify left bottom)
				(hide yes)
			)
		)
		(property "Datasheet" "https://www.murata.com/products/productdetail?partno=GRM155R61H104KE14%23"
			(at 238.76 77.47 0)
			(effects
				(font
					(size 1.27 1.27)
					(thickness 0.15)
				)
				(justify left bottom)
				(hide yes)
			)
		)
		(property "Description" ""
			(at 223.52 97.79 0)
			(effects
				(font
					(size 1.27 1.27)
				)
				(hide yes)
			)
		)
		(property "MPN" "GRM155R61H104KE14D"
			(at 241.3 77.47 0)
			(effects
				(font
					(size 1.27 1.27)
					(thickness 0.15)
				)
				(justify left bottom)
				(hide yes)
			)
		)
		(property "Manufacturer" "Murata"
			(at 243.84 77.47 0)
			(effects
				(font
					(size 1.27 1.27)
					(thickness 0.15)
				)
				(justify left bottom)
				(hide yes)
			)
		)
		(property "License" "Apache-2.0"
			(at 246.38 77.47 0)
			(effects
				(font
					(size 1.27 1.27)
					(thickness 0.15)
				)
				(justify left bottom)
				(hide yes)
			)
		)
		(property "Author" "Antmicro"
			(at 248.92 77.47 0)
			(effects
				(font
					(size 1.27 1.27)
					(thickness 0.15)
				)
				(justify left bottom)
				(hide yes)
			)
		)
		(property "Val" "100n"
			(at 224.155 97.79 90)
			(effects
				(font
					(size 1.27 1.27)
					(thickness 0.15)
				)
				(justify right)
			)
		)
		(property "Voltage" "50V"
			(at 251.46 77.47 0)
			(effects
				(font
					(size 1.27 1.27)
				)
				(justify left bottom)
				(hide yes)
			)
		)
		(property "Dielectric" "X5R"
			(at 254 77.47 0)
			(effects
				(font
					(size 1.27 1.27)
				)
				(justify left bottom)
				(hide yes)
			)
		)
		(pin "1"
		)
		(pin "2"
		)
		(instances
			(project "gmsl-serializer"
				(path ""
					(reference "C20")
					(unit 1)
				)
			)
		)
	)
	(symbol
		(lib_id "antmicroResistors0402:R_0R_0402")
		(at 63.5 96.52 270)
		(mirror x)
		(unit 1)
		(exclude_from_sim no)
		(in_bom yes)
		(on_board yes)
		(dnp no)
		(property "Reference" "R20"
			(at 67.945 93.98 0)
			(effects
				(font
					(size 1.27 1.27)
					(thickness 0.15)
				)
			)
		)
		(property "Value" "R_0R_0402"
			(at 50.8 76.2 0)
			(effects
				(font
					(size 1.27 1.27)
					(thickness 0.15)
				)
				(justify left bottom)
				(hide yes)
			)
		)
		(property "Footprint" "antmicro-footprints:R_0402_1005Metric"
			(at 48.26 76.2 0)
			(effects
				(font
					(size 1.27 1.27)
					(thickness 0.15)
				)
				(justify left bottom)
				(hide yes)
			)
		)
		(property "Datasheet" "https://industrial.panasonic.com/cdbs/www-data/pdf/RDA0000/AOA0000C301.pdf"
			(at 45.72 76.2 0)
			(effects
				(font
					(size 1.27 1.27)
					(thickness 0.15)
				)
				(justify left bottom)
				(hide yes)
			)
		)
		(property "Description" ""
			(at 63.5 96.52 0)
			(effects
				(font
					(size 1.27 1.27)
				)
				(hide yes)
			)
		)
		(property "MPN" "ERJ2GE0R00X"
			(at 43.18 76.2 0)
			(effects
				(font
					(size 1.27 1.27)
					(thickness 0.15)
				)
				(justify left bottom)
				(hide yes)
			)
		)
		(property "Manufacturer" "Panasonic"
			(at 40.64 76.2 0)
			(effects
				(font
					(size 1.27 1.27)
					(thickness 0.15)
				)
				(justify left bottom)
				(hide yes)
			)
		)
		(property "License" "Apache-2.0"
			(at 38.1 76.2 0)
			(effects
				(font
					(size 1.27 1.27)
					(thickness 0.15)
				)
				(justify left bottom)
				(hide yes)
			)
		)
		(property "Author" "Antmicro"
			(at 35.56 76.2 0)
			(effects
				(font
					(size 1.27 1.27)
					(thickness 0.15)
				)
				(justify left bottom)
				(hide yes)
			)
		)
		(property "Val" "0R"
			(at 66.04 93.98 0)
			(effects
				(font
					(size 1.27 1.27)
					(thickness 0.15)
				)
			)
		)
		(property "Tolerance" "~"
			(at 53.34 76.2 0)
			(effects
				(font
					(size 1.27 1.27)
				)
				(justify left bottom)
				(hide yes)
			)
		)
		(property "Current" "1A"
			(at 33.02 76.2 0)
			(effects
				(font
					(size 1.27 1.27)
					(thickness 0.15)
				)
				(justify left bottom)
				(hide yes)
			)
		)
		(pin "1"
		)
		(pin "2"
		)
		(instances
			(project "gmsl-serializer"
				(path ""
					(reference "R20")
					(unit 1)
				)
			)
		)
	)
	(symbol
		(lib_id "antmicroResonators:Resonator_25MHz_ABM8G")
		(at 53.34 101.6 0)
		(unit 1)
		(exclude_from_sim no)
		(in_bom yes)
		(on_board yes)
		(dnp no)
		(property "Reference" "Y1"
			(at 57.15 95.25 0)
			(effects
				(font
					(size 1.27 1.27)
					(thickness 0.15)
				)
			)
		)
		(property "Value" "Resonator_25MHz_ABM8G"
			(at 68.58 114.3 0)
			(effects
				(font
					(size 1.27 1.27)
					(thickness 0.15)
				)
				(justify left bottom)
				(hide yes)
			)
		)
		(property "Footprint" "antmicro-footprints:Resonator_SMD_Abracon_ABM8G_3.2x2.5mm"
			(at 68.58 116.84 0)
			(effects
				(font
					(size 1.27 1.27)
					(thickness 0.15)
				)
				(justify left bottom)
				(hide yes)
			)
		)
		(property "Datasheet" "https://abracon.com/Resonators/ABM8G.pdf"
			(at 68.58 119.38 0)
			(effects
				(font
					(size 1.27 1.27)
					(thickness 0.15)
				)
				(justify left bottom)
				(hide yes)
			)
		)
		(property "Description" ""
			(at 53.34 101.6 0)
			(effects
				(font
					(size 1.27 1.27)
				)
				(hide yes)
			)
		)
		(property "MPN" "ABM8G-25.000MHZ-18-D2Y-T3"
			(at 68.58 109.22 0)
			(effects
				(font
					(size 1.27 1.27)
					(thickness 0.15)
				)
				(justify left bottom)
				(hide yes)
			)
		)
		(property "Manufacturer" "Abracon"
			(at 68.58 121.92 0)
			(effects
				(font
					(size 1.27 1.27)
					(thickness 0.15)
				)
				(justify left bottom)
				(hide yes)
			)
		)
		(property "Author" "Antmicro"
			(at 68.58 124.46 0)
			(effects
				(font
					(size 1.27 1.27)
					(thickness 0.15)
				)
				(justify left bottom)
				(hide yes)
			)
		)
		(property "License" "Apache-2.0"
			(at 68.58 127 0)
			(effects
				(font
					(size 1.27 1.27)
					(thickness 0.15)
				)
				(justify left bottom)
				(hide yes)
			)
		)
		(property "Val" "25 MHz"
			(at 57.15 97.79 0)
			(effects
				(font
					(size 1.27 1.27)
					(thickness 0.15)
				)
			)
		)
		(pin "1"
		)
		(pin "2"
		)
		(pin "3"
		)
		(pin "4"
		)
		(instances
			(project "gmsl-serializer"
				(path ""
					(reference "Y1")
					(unit 1)
				)
			)
		)
	)
	(symbol
		(lib_id "antmicroResistors0402:R_10k_0402")
		(at 45.72 212.09 90)
		(unit 1)
		(exclude_from_sim no)
		(in_bom yes)
		(on_board yes)
		(dnp no)
		(property "Reference" "R19"
			(at 47.625 208.28 90)
			(effects
				(font
					(size 1.27 1.27)
					(thickness 0.15)
				)
				(justify right)
			)
		)
		(property "Value" "R_10k_0402"
			(at 58.42 191.77 0)
			(effects
				(font
					(size 1.27 1.27)
					(thickness 0.15)
				)
				(justify left bottom)
				(hide yes)
			)
		)
		(property "Footprint" "antmicro-footprints:R_0402_1005Metric"
			(at 60.96 191.77 0)
			(effects
				(font
					(size 1.27 1.27)
					(thickness 0.15)
				)
				(justify left bottom)
				(hide yes)
			)
		)
		(property "Datasheet" "https://www.bourns.com/docs/product-datasheets/cr.pdf"
			(at 63.5 191.77 0)
			(effects
				(font
					(size 1.27 1.27)
					(thickness 0.15)
				)
				(justify left bottom)
				(hide yes)
			)
		)
		(property "Description" ""
			(at 45.72 212.09 0)
			(effects
				(font
					(size 1.27 1.27)
				)
				(hide yes)
			)
		)
		(property "MPN" "CR0402-FX-1002GLF"
			(at 66.04 191.77 0)
			(effects
				(font
					(size 1.27 1.27)
					(thickness 0.15)
				)
				(justify left bottom)
				(hide yes)
			)
		)
		(property "Manufacturer" "Bourns"
			(at 68.58 191.77 0)
			(effects
				(font
					(size 1.27 1.27)
					(thickness 0.15)
				)
				(justify left bottom)
				(hide yes)
			)
		)
		(property "License" "Apache-2.0"
			(at 71.12 191.77 0)
			(effects
				(font
					(size 1.27 1.27)
					(thickness 0.15)
				)
				(justify left bottom)
				(hide yes)
			)
		)
		(property "Author" "Antmicro"
			(at 73.66 191.77 0)
			(effects
				(font
					(size 1.27 1.27)
					(thickness 0.15)
				)
				(justify left bottom)
				(hide yes)
			)
		)
		(property "Val" "10k"
			(at 47.625 210.82 90)
			(effects
				(font
					(size 1.27 1.27)
					(thickness 0.15)
				)
				(justify right)
			)
		)
		(property "Tolerance" "1%"
			(at 55.88 191.77 0)
			(effects
				(font
					(size 1.27 1.27)
				)
				(justify left bottom)
				(hide yes)
			)
		)
		(pin "1"
		)
		(pin "2"
		)
		(instances
			(project "gmsl-serializer"
				(path ""
					(reference "R19")
					(unit 1)
				)
			)
		)
	)
	(symbol
		(lib_id "antmicropower:+1V8")
		(at 215.9 111.76 0)
		(mirror y)
		(unit 1)
		(exclude_from_sim no)
		(in_bom yes)
		(on_board yes)
		(dnp no)
		(property "Reference" "#PWR0146"
			(at 200.66 114.3 0)
			(effects
				(font
					(size 1.27 1.27)
					(thickness 0.15)
				)
				(justify left bottom)
				(hide yes)
			)
		)
		(property "Value" "+1V8"
			(at 215.9 107.95 0)
			(effects
				(font
					(size 1.27 1.27)
					(thickness 0.15)
				)
			)
		)
		(property "Footprint" ""
			(at 200.66 119.38 0)
			(effects
				(font
					(size 1.27 1.27)
					(thickness 0.15)
				)
				(justify left bottom)
				(hide yes)
			)
		)
		(property "Datasheet" ""
			(at 200.66 121.92 0)
			(effects
				(font
					(size 1.27 1.27)
					(thickness 0.15)
				)
				(justify left bottom)
				(hide yes)
			)
		)
		(property "Description" ""
			(at 215.9 111.76 0)
			(effects
				(font
					(size 1.27 1.27)
				)
				(hide yes)
			)
		)
		(property "Author" "Antmicro"
			(at 200.66 119.38 0)
			(effects
				(font
					(size 1.27 1.27)
					(thickness 0.15)
				)
				(justify left bottom)
				(hide yes)
			)
		)
		(property "License" "Apache-2.0"
			(at 200.66 121.92 0)
			(effects
				(font
					(size 1.27 1.27)
					(thickness 0.15)
				)
				(justify left bottom)
				(hide yes)
			)
		)
		(pin "1"
		)
		(instances
			(project "gmsl-serializer"
				(path ""
					(reference "#PWR0146")
					(unit 1)
				)
			)
		)
	)
	(symbol
		(lib_id "antmicroResistors0402:R_10k_0402")
		(at 82.55 212.09 90)
		(unit 1)
		(exclude_from_sim no)
		(in_bom no)
		(on_board yes)
		(dnp yes)
		(property "Reference" "R22"
			(at 84.455 208.28 90)
			(effects
				(font
					(size 1.27 1.27)
					(thickness 0.15)
				)
				(justify right)
			)
		)
		(property "Value" "R_10k_0402"
			(at 95.25 191.77 0)
			(effects
				(font
					(size 1.27 1.27)
					(thickness 0.15)
				)
				(justify left bottom)
				(hide yes)
			)
		)
		(property "Footprint" "antmicro-footprints:R_0402_1005Metric"
			(at 97.79 191.77 0)
			(effects
				(font
					(size 1.27 1.27)
					(thickness 0.15)
				)
				(justify left bottom)
				(hide yes)
			)
		)
		(property "Datasheet" "https://www.bourns.com/docs/product-datasheets/cr.pdf"
			(at 100.33 191.77 0)
			(effects
				(font
					(size 1.27 1.27)
					(thickness 0.15)
				)
				(justify left bottom)
				(hide yes)
			)
		)
		(property "Description" ""
			(at 82.55 212.09 0)
			(effects
				(font
					(size 1.27 1.27)
				)
				(hide yes)
			)
		)
		(property "MPN" "CR0402-FX-1002GLF"
			(at 102.87 191.77 0)
			(effects
				(font
					(size 1.27 1.27)
					(thickness 0.15)
				)
				(justify left bottom)
				(hide yes)
			)
		)
		(property "Manufacturer" "Bourns"
			(at 105.41 191.77 0)
			(effects
				(font
					(size 1.27 1.27)
					(thickness 0.15)
				)
				(justify left bottom)
				(hide yes)
			)
		)
		(property "License" "Apache-2.0"
			(at 107.95 191.77 0)
			(effects
				(font
					(size 1.27 1.27)
					(thickness 0.15)
				)
				(justify left bottom)
				(hide yes)
			)
		)
		(property "Author" "Antmicro"
			(at 110.49 191.77 0)
			(effects
				(font
					(size 1.27 1.27)
					(thickness 0.15)
				)
				(justify left bottom)
				(hide yes)
			)
		)
		(property "Val" "10k"
			(at 84.455 210.82 90)
			(effects
				(font
					(size 1.27 1.27)
					(thickness 0.15)
				)
				(justify right)
			)
		)
		(property "Tolerance" "1%"
			(at 92.71 191.77 0)
			(effects
				(font
					(size 1.27 1.27)
				)
				(justify left bottom)
				(hide yes)
			)
		)
		(pin "1"
		)
		(pin "2"
		)
		(instances
			(project "gmsl-serializer"
				(path ""
					(reference "R22")
					(unit 1)
				)
			)
		)
	)
	(symbol
		(lib_id "antmicropower:GND")
		(at 215.9 101.6 0)
		(unit 1)
		(exclude_from_sim no)
		(in_bom yes)
		(on_board yes)
		(dnp no)
		(property "Reference" "#PWR0145"
			(at 224.79 104.14 0)
			(effects
				(font
					(size 1.27 1.27)
					(thickness 0.15)
				)
				(justify left bottom)
				(hide yes)
			)
		)
		(property "Value" "GND"
			(at 215.9 105.41 0)
			(effects
				(font
					(size 1.27 1.27)
					(thickness 0.15)
				)
			)
		)
		(property "Footprint" ""
			(at 224.79 109.22 0)
			(effects
				(font
					(size 1.27 1.27)
					(thickness 0.15)
				)
				(justify left bottom)
				(hide yes)
			)
		)
		(property "Datasheet" ""
			(at 224.79 114.3 0)
			(effects
				(font
					(size 1.27 1.27)
					(thickness 0.15)
				)
				(justify left bottom)
				(hide yes)
			)
		)
		(property "Description" ""
			(at 215.9 101.6 0)
			(effects
				(font
					(size 1.27 1.27)
				)
				(hide yes)
			)
		)
		(property "Author" "Antmicro"
			(at 224.79 109.22 0)
			(effects
				(font
					(size 1.27 1.27)
					(thickness 0.15)
				)
				(justify left bottom)
				(hide yes)
			)
		)
		(property "License" "Apache-2.0"
			(at 224.79 111.76 0)
			(effects
				(font
					(size 1.27 1.27)
					(thickness 0.15)
				)
				(justify left bottom)
				(hide yes)
			)
		)
		(pin "1"
		)
		(instances
			(project "gmsl-serializer"
				(path ""
					(reference "#PWR0145")
					(unit 1)
				)
			)
		)
	)
	(symbol
		(lib_id "antmicroCapacitors0402:C_10n_0402")
		(at 223.52 119.38 90)
		(unit 1)
		(exclude_from_sim no)
		(in_bom yes)
		(on_board yes)
		(dnp no)
		(property "Reference" "C27"
			(at 224.79 115.57 90)
			(effects
				(font
					(size 1.27 1.27)
					(thickness 0.15)
				)
				(justify right)
			)
		)
		(property "Value" "C_10n_0402"
			(at 233.68 99.06 0)
			(effects
				(font
					(size 1.27 1.27)
					(thickness 0.15)
				)
				(justify left bottom)
				(hide yes)
			)
		)
		(property "Footprint" "antmicro-footprints:C_0402_1005Metric"
			(at 236.22 99.06 0)
			(effects
				(font
					(size 1.27 1.27)
					(thickness 0.15)
				)
				(justify left bottom)
				(hide yes)
			)
		)
		(property "Datasheet" "https://www.murata.com/products/productdetail?partno=GRM155R71H103KA88%23"
			(at 238.76 99.06 0)
			(effects
				(font
					(size 1.27 1.27)
					(thickness 0.15)
				)
				(justify left bottom)
				(hide yes)
			)
		)
		(property "Description" ""
			(at 223.52 119.38 0)
			(effects
				(font
					(size 1.27 1.27)
				)
				(hide yes)
			)
		)
		(property "MPN" "GRM155R71H103KA88D"
			(at 241.3 99.06 0)
			(effects
				(font
					(size 1.27 1.27)
					(thickness 0.15)
				)
				(justify left bottom)
				(hide yes)
			)
		)
		(property "Manufacturer" "Murata"
			(at 243.84 99.06 0)
			(effects
				(font
					(size 1.27 1.27)
					(thickness 0.15)
				)
				(justify left bottom)
				(hide yes)
			)
		)
		(property "License" "Apache-2.0"
			(at 246.38 99.06 0)
			(effects
				(font
					(size 1.27 1.27)
					(thickness 0.15)
				)
				(justify left bottom)
				(hide yes)
			)
		)
		(property "Author" "Antmicro"
			(at 248.92 99.06 0)
			(effects
				(font
					(size 1.27 1.27)
					(thickness 0.15)
				)
				(justify left bottom)
				(hide yes)
			)
		)
		(property "Val" "10n"
			(at 224.79 118.11 90)
			(effects
				(font
					(size 1.27 1.27)
					(thickness 0.15)
				)
				(justify right)
			)
		)
		(property "Voltage" "50V"
			(at 251.46 99.06 0)
			(effects
				(font
					(size 1.27 1.27)
				)
				(justify left bottom)
				(hide yes)
			)
		)
		(property "Dielectric" "X7R"
			(at 254 99.06 0)
			(effects
				(font
					(size 1.27 1.27)
				)
				(justify left bottom)
				(hide yes)
			)
		)
		(pin "1"
		)
		(pin "2"
		)
		(instances
			(project "gmsl-serializer"
				(path ""
					(reference "C27")
					(unit 1)
				)
			)
		)
	)
	(symbol
		(lib_id "antmicropower:GND")
		(at 233.68 185.42 0)
		(mirror y)
		(unit 1)
		(exclude_from_sim no)
		(in_bom yes)
		(on_board yes)
		(dnp no)
		(property "Reference" "#PWR0151"
			(at 224.79 187.96 0)
			(effects
				(font
					(size 1.27 1.27)
					(thickness 0.15)
				)
				(justify left bottom)
				(hide yes)
			)
		)
		(property "Value" "GND"
			(at 233.68 189.23 0)
			(effects
				(font
					(size 1.27 1.27)
					(thickness 0.15)
				)
			)
		)
		(property "Footprint" ""
			(at 224.79 193.04 0)
			(effects
				(font
					(size 1.27 1.27)
					(thickness 0.15)
				)
				(justify left bottom)
				(hide yes)
			)
		)
		(property "Datasheet" ""
			(at 224.79 198.12 0)
			(effects
				(font
					(size 1.27 1.27)
					(thickness 0.15)
				)
				(justify left bottom)
				(hide yes)
			)
		)
		(property "Description" ""
			(at 233.68 185.42 0)
			(effects
				(font
					(size 1.27 1.27)
				)
				(hide yes)
			)
		)
		(property "Author" "Antmicro"
			(at 224.79 193.04 0)
			(effects
				(font
					(size 1.27 1.27)
					(thickness 0.15)
				)
				(justify left bottom)
				(hide yes)
			)
		)
		(property "License" "Apache-2.0"
			(at 224.79 195.58 0)
			(effects
				(font
					(size 1.27 1.27)
					(thickness 0.15)
				)
				(justify left bottom)
				(hide yes)
			)
		)
		(pin "1"
		)
		(instances
			(project "gmsl-serializer"
				(path ""
					(reference "#PWR0151")
					(unit 1)
				)
			)
		)
	)
	(symbol
		(lib_id "antmicroCapacitors0402:C_10u_0402")
		(at 227.33 184.15 90)
		(unit 1)
		(exclude_from_sim no)
		(in_bom yes)
		(on_board yes)
		(dnp no)
		(property "Reference" "C26"
			(at 227.965 179.705 90)
			(effects
				(font
					(size 1.27 1.27)
					(thickness 0.15)
				)
				(justify right)
			)
		)
		(property "Value" "C_10u_0402"
			(at 237.49 163.83 0)
			(effects
				(font
					(size 1.27 1.27)
					(thickness 0.15)
				)
				(justify left bottom)
				(hide yes)
			)
		)
		(property "Footprint" "antmicro-footprints:C_0402_1005Metric"
			(at 240.03 163.83 0)
			(effects
				(font
					(size 1.27 1.27)
					(thickness 0.15)
				)
				(justify left bottom)
				(hide yes)
			)
		)
		(property "Datasheet" "https://www.yageo.com/en/Chart/Download/pdf/CC0402MRX5R5BB106"
			(at 242.57 163.83 0)
			(effects
				(font
					(size 1.27 1.27)
					(thickness 0.15)
				)
				(justify left bottom)
				(hide yes)
			)
		)
		(property "Description" ""
			(at 227.33 184.15 0)
			(effects
				(font
					(size 1.27 1.27)
				)
				(hide yes)
			)
		)
		(property "MPN" "CC0402MRX5R5BB106"
			(at 245.11 163.83 0)
			(effects
				(font
					(size 1.27 1.27)
					(thickness 0.15)
				)
				(justify left bottom)
				(hide yes)
			)
		)
		(property "Manufacturer" "YAGEO"
			(at 247.65 163.83 0)
			(effects
				(font
					(size 1.27 1.27)
					(thickness 0.15)
				)
				(justify left bottom)
				(hide yes)
			)
		)
		(property "License" "Apache-2.0"
			(at 250.19 163.83 0)
			(effects
				(font
					(size 1.27 1.27)
					(thickness 0.15)
				)
				(justify left bottom)
				(hide yes)
			)
		)
		(property "Author" "Antmicro"
			(at 252.73 163.83 0)
			(effects
				(font
					(size 1.27 1.27)
					(thickness 0.15)
				)
				(justify left bottom)
				(hide yes)
			)
		)
		(property "Val" "10u"
			(at 227.965 183.515 90)
			(effects
				(font
					(size 1.27 1.27)
					(thickness 0.15)
				)
				(justify right)
			)
		)
		(property "Voltage" ""
			(at 255.27 163.83 0)
			(effects
				(font
					(size 1.27 1.27)
				)
				(justify left bottom)
				(hide yes)
			)
		)
		(property "Dielectric" ""
			(at 257.81 163.83 0)
			(effects
				(font
					(size 1.27 1.27)
				)
				(justify left bottom)
				(hide yes)
			)
		)
		(pin "1"
		)
		(pin "2"
		)
		(instances
			(project "gmsl-serializer"
				(path ""
					(reference "C26")
					(unit 1)
				)
			)
		)
	)
)
